FILE_TYPE = MACRO_DRAWING;
SET COLOR_WIRE YELLOW;
SET COLOR_PROP ORANGE;
SET COLOR_DOT WHITE;
SET COLOR_ARC YELLOW;
SET COLOR_BODY GREEN;
SET COLOR_NOTE PURPLE;
SET PROP_DISPLAY VALUE;
SET PAGE_NUMBER P105;
FORCEADD UNIVERSAL_GND..1
(-2625 -100);
FORCEPROP 3 LASTPIN (-2625 -50) SIG_NAME GND\g
J 0
(-2615 -40);
DISPLAY 0.659574 (-2615 -40);
PAINT MONO (-2615 -40);
DISPLAY INVISIBLE (-2615 -40);
FORCEPROP 1 LAST PATH I1
J 0
(-2550 -100);
DISPLAY 0.872340 (-2550 -100);
PAINT AQUA (-2550 -100);
DISPLAY INVISIBLE (-2550 -100);
FORCEPROP 1 LAST HDL_POWER GND
J 1
(-2600 -175);
DISPLAY 0.872340 (-2600 -175);
PAINT GREEN (-2600 -175);
DISPLAY INVISIBLE (-2600 -175);
FORCEPROP 2 LAST CDS_LIB logical_power
J 0
(-2625 -100);
PAINT MONO (-2625 -100);
DISPLAY INVISIBLE (-2625 -100);
FORCEADD OFFPAGE..1
(-3775 2025);
FORCEPROP 2 LAST $XR3 104 
J 0
(-4147 1989);
DISPLAY 0.638298 (-4147 1989);
PAINT MONO (-4147 1989);
FORCEPROP 2 LAST $XR2 103 
J 0
(-4027 1989);
DISPLAY 0.638298 (-4027 1989);
PAINT MONO (-4027 1989);
FORCEPROP 2 LAST $XR1 102 
J 0
(-4147 2025);
DISPLAY 0.638298 (-4147 2025);
PAINT MONO (-4147 2025);
FORCEPROP 2 LAST $XR0 130 
J 0
(-4027 2025);
DISPLAY 0.638298 (-4027 2025);
PAINT MONO (-4027 2025);
FORCEPROP 2 LAST CDS_LIB standard
J 0
(-3775 2025);
PAINT MONO (-3775 2025);
DISPLAY INVISIBLE (-3775 2025);
FORCEPROP 1 LAST OFFPAGE TRUE
J 0
(-3450 1900);
DISPLAY 0.872340 (-3450 1900);
DISPLAY INVISIBLE (-3450 1900);
FORCEPROP 1 LAST COMMENT_BODY TRUE
J 0
(-3650 1925);
DISPLAY 0.872340 (-3650 1925);
PAINT GREEN (-3650 1925);
DISPLAY INVISIBLE (-3650 1925);
FORCEPROP 2 LAST PATH I10
J 0
(-3725 2100);
DISPLAY 1.021277 (-3725 2100);
DISPLAY INVISIBLE (-3725 2100);
FORCEADD TAP..1
(-1200 3475);
FORCEPROP 3 LASTPIN (-1250 3475) SIG_NAME M_D_CPU1_SA_DQ<15>
J 0
(-1240 3485);
DISPLAY 0.659574 (-1240 3485);
PAINT MONO (-1240 3485);
DISPLAY INVISIBLE (-1240 3485);
FORCEPROP 1 LASTPIN (-1250 3475) BN 15
J 0
(-1262 3483);
DISPLAY 0.680851 (-1262 3483);
PAINT GREEN (-1262 3483);
FORCEPROP 2 LAST CDS_LIB standard
J 0
(-1200 3475);
PAINT MONO (-1200 3475);
DISPLAY INVISIBLE (-1200 3475);
FORCEPROP 1 LAST BODY_TYPE PLUMBING
J 0
(-1200 3525);
DISPLAY 0.872340 (-1200 3525);
PAINT GREEN (-1200 3525);
DISPLAY INVISIBLE (-1200 3525);
FORCEPROP 1 LAST HDL_TAP TRUE
J 0
(-875 3350);
DISPLAY 0.872340 (-875 3350);
DISPLAY INVISIBLE (-875 3350);
FORCEPROP 1 LAST PATH I100
J 0
(-1202 3475);
DISPLAY 0.872340 (-1202 3475);
PAINT GREEN (-1202 3475);
DISPLAY INVISIBLE (-1202 3475);
FORCEADD TAP..1
(-1200 3575);
FORCEPROP 3 LASTPIN (-1250 3575) SIG_NAME M_D_CPU1_SA_DQ<17>
J 0
(-1240 3585);
DISPLAY 0.659574 (-1240 3585);
PAINT MONO (-1240 3585);
DISPLAY INVISIBLE (-1240 3585);
FORCEPROP 1 LASTPIN (-1250 3575) BN 17
J 0
(-1262 3583);
DISPLAY 0.680851 (-1262 3583);
PAINT GREEN (-1262 3583);
FORCEPROP 2 LAST CDS_LIB standard
J 0
(-1200 3575);
PAINT MONO (-1200 3575);
DISPLAY INVISIBLE (-1200 3575);
FORCEPROP 1 LAST BODY_TYPE PLUMBING
J 0
(-1200 3625);
DISPLAY 0.872340 (-1200 3625);
PAINT GREEN (-1200 3625);
DISPLAY INVISIBLE (-1200 3625);
FORCEPROP 1 LAST HDL_TAP TRUE
J 0
(-875 3450);
DISPLAY 0.872340 (-875 3450);
DISPLAY INVISIBLE (-875 3450);
FORCEPROP 1 LAST PATH I101
J 0
(-1202 3575);
DISPLAY 0.872340 (-1202 3575);
PAINT GREEN (-1202 3575);
DISPLAY INVISIBLE (-1202 3575);
FORCEADD TAP..1
(-1200 3625);
FORCEPROP 3 LASTPIN (-1250 3625) SIG_NAME M_D_CPU1_SA_DQ<18>
J 0
(-1240 3635);
DISPLAY 0.659574 (-1240 3635);
PAINT MONO (-1240 3635);
DISPLAY INVISIBLE (-1240 3635);
FORCEPROP 1 LASTPIN (-1250 3625) BN 18
J 0
(-1262 3633);
DISPLAY 0.680851 (-1262 3633);
PAINT GREEN (-1262 3633);
FORCEPROP 2 LAST CDS_LIB standard
J 0
(-1200 3625);
PAINT MONO (-1200 3625);
DISPLAY INVISIBLE (-1200 3625);
FORCEPROP 1 LAST BODY_TYPE PLUMBING
J 0
(-1200 3675);
DISPLAY 0.872340 (-1200 3675);
PAINT GREEN (-1200 3675);
DISPLAY INVISIBLE (-1200 3675);
FORCEPROP 1 LAST HDL_TAP TRUE
J 0
(-875 3500);
DISPLAY 0.872340 (-875 3500);
DISPLAY INVISIBLE (-875 3500);
FORCEPROP 1 LAST PATH I102
J 0
(-1202 3625);
DISPLAY 0.872340 (-1202 3625);
PAINT GREEN (-1202 3625);
DISPLAY INVISIBLE (-1202 3625);
FORCEADD TAP..1
(-1200 3675);
FORCEPROP 3 LASTPIN (-1250 3675) SIG_NAME M_D_CPU1_SA_DQ<19>
J 0
(-1240 3685);
DISPLAY 0.659574 (-1240 3685);
PAINT MONO (-1240 3685);
DISPLAY INVISIBLE (-1240 3685);
FORCEPROP 1 LASTPIN (-1250 3675) BN 19
J 0
(-1262 3683);
DISPLAY 0.680851 (-1262 3683);
PAINT GREEN (-1262 3683);
FORCEPROP 2 LAST CDS_LIB standard
J 0
(-1200 3675);
PAINT MONO (-1200 3675);
DISPLAY INVISIBLE (-1200 3675);
FORCEPROP 1 LAST BODY_TYPE PLUMBING
J 0
(-1200 3725);
DISPLAY 0.872340 (-1200 3725);
PAINT GREEN (-1200 3725);
DISPLAY INVISIBLE (-1200 3725);
FORCEPROP 1 LAST HDL_TAP TRUE
J 0
(-875 3550);
DISPLAY 0.872340 (-875 3550);
DISPLAY INVISIBLE (-875 3550);
FORCEPROP 1 LAST PATH I103
J 0
(-1202 3675);
DISPLAY 0.872340 (-1202 3675);
PAINT GREEN (-1202 3675);
DISPLAY INVISIBLE (-1202 3675);
FORCEADD TAP..1
(-1200 3725);
FORCEPROP 3 LASTPIN (-1250 3725) SIG_NAME M_D_CPU1_SA_DQ<20>
J 0
(-1240 3735);
DISPLAY 0.659574 (-1240 3735);
PAINT MONO (-1240 3735);
DISPLAY INVISIBLE (-1240 3735);
FORCEPROP 1 LASTPIN (-1250 3725) BN 20
J 0
(-1262 3733);
DISPLAY 0.680851 (-1262 3733);
PAINT GREEN (-1262 3733);
FORCEPROP 2 LAST CDS_LIB standard
J 0
(-1200 3725);
PAINT MONO (-1200 3725);
DISPLAY INVISIBLE (-1200 3725);
FORCEPROP 1 LAST BODY_TYPE PLUMBING
J 0
(-1200 3775);
DISPLAY 0.872340 (-1200 3775);
PAINT GREEN (-1200 3775);
DISPLAY INVISIBLE (-1200 3775);
FORCEPROP 1 LAST HDL_TAP TRUE
J 0
(-875 3600);
DISPLAY 0.872340 (-875 3600);
DISPLAY INVISIBLE (-875 3600);
FORCEPROP 1 LAST PATH I104
J 0
(-1202 3725);
DISPLAY 0.872340 (-1202 3725);
PAINT GREEN (-1202 3725);
DISPLAY INVISIBLE (-1202 3725);
FORCEADD TAP..1
(-1200 3775);
FORCEPROP 3 LASTPIN (-1250 3775) SIG_NAME M_D_CPU1_SA_DQ<21>
J 0
(-1240 3785);
DISPLAY 0.659574 (-1240 3785);
PAINT MONO (-1240 3785);
DISPLAY INVISIBLE (-1240 3785);
FORCEPROP 1 LASTPIN (-1250 3775) BN 21
J 0
(-1262 3783);
DISPLAY 0.680851 (-1262 3783);
PAINT GREEN (-1262 3783);
FORCEPROP 2 LAST CDS_LIB standard
J 0
(-1200 3775);
PAINT MONO (-1200 3775);
DISPLAY INVISIBLE (-1200 3775);
FORCEPROP 1 LAST BODY_TYPE PLUMBING
J 0
(-1200 3825);
DISPLAY 0.872340 (-1200 3825);
PAINT GREEN (-1200 3825);
DISPLAY INVISIBLE (-1200 3825);
FORCEPROP 1 LAST HDL_TAP TRUE
J 0
(-875 3650);
DISPLAY 0.872340 (-875 3650);
DISPLAY INVISIBLE (-875 3650);
FORCEPROP 1 LAST PATH I105
J 0
(-1202 3775);
DISPLAY 0.872340 (-1202 3775);
PAINT GREEN (-1202 3775);
DISPLAY INVISIBLE (-1202 3775);
FORCEADD TAP..1
(-1200 3825);
FORCEPROP 3 LASTPIN (-1250 3825) SIG_NAME M_D_CPU1_SA_DQ<22>
J 0
(-1240 3835);
DISPLAY 0.659574 (-1240 3835);
PAINT MONO (-1240 3835);
DISPLAY INVISIBLE (-1240 3835);
FORCEPROP 1 LASTPIN (-1250 3825) BN 22
J 0
(-1262 3833);
DISPLAY 0.680851 (-1262 3833);
PAINT GREEN (-1262 3833);
FORCEPROP 2 LAST CDS_LIB standard
J 0
(-1200 3825);
DISPLAY INVISIBLE (-1200 3825);
FORCEPROP 1 LAST BODY_TYPE PLUMBING
J 0
(-1200 3875);
DISPLAY 0.872340 (-1200 3875);
PAINT GREEN (-1200 3875);
DISPLAY INVISIBLE (-1200 3875);
FORCEPROP 1 LAST HDL_TAP TRUE
J 0
(-875 3700);
DISPLAY 0.872340 (-875 3700);
DISPLAY INVISIBLE (-875 3700);
FORCEPROP 1 LAST PATH I106
J 0
(-1202 3825);
DISPLAY 0.872340 (-1202 3825);
PAINT GREEN (-1202 3825);
DISPLAY INVISIBLE (-1202 3825);
FORCEADD TAP..1
(-1200 3875);
FORCEPROP 3 LASTPIN (-1250 3875) SIG_NAME M_D_CPU1_SA_DQ<23>
J 0
(-1240 3885);
DISPLAY 0.659574 (-1240 3885);
PAINT MONO (-1240 3885);
DISPLAY INVISIBLE (-1240 3885);
FORCEPROP 1 LASTPIN (-1250 3875) BN 23
J 0
(-1262 3883);
DISPLAY 0.680851 (-1262 3883);
PAINT GREEN (-1262 3883);
FORCEPROP 2 LAST CDS_LIB standard
J 0
(-1200 3875);
DISPLAY INVISIBLE (-1200 3875);
FORCEPROP 1 LAST BODY_TYPE PLUMBING
J 0
(-1200 3925);
DISPLAY 0.872340 (-1200 3925);
PAINT GREEN (-1200 3925);
DISPLAY INVISIBLE (-1200 3925);
FORCEPROP 1 LAST HDL_TAP TRUE
J 0
(-875 3750);
DISPLAY 0.872340 (-875 3750);
DISPLAY INVISIBLE (-875 3750);
FORCEPROP 1 LAST PATH I107
J 0
(-1202 3875);
DISPLAY 0.872340 (-1202 3875);
PAINT GREEN (-1202 3875);
DISPLAY INVISIBLE (-1202 3875);
FORCEADD TAP..1
(-1200 3975);
FORCEPROP 3 LASTPIN (-1250 3975) SIG_NAME M_D_CPU1_SA_DQ<25>
J 0
(-1240 3985);
DISPLAY 0.659574 (-1240 3985);
PAINT MONO (-1240 3985);
DISPLAY INVISIBLE (-1240 3985);
FORCEPROP 1 LASTPIN (-1250 3975) BN 25
J 0
(-1262 3983);
DISPLAY 0.680851 (-1262 3983);
PAINT GREEN (-1262 3983);
FORCEPROP 2 LAST CDS_LIB standard
J 0
(-1200 3975);
DISPLAY INVISIBLE (-1200 3975);
FORCEPROP 1 LAST BODY_TYPE PLUMBING
J 0
(-1200 4025);
DISPLAY 0.872340 (-1200 4025);
PAINT GREEN (-1200 4025);
DISPLAY INVISIBLE (-1200 4025);
FORCEPROP 1 LAST HDL_TAP TRUE
J 0
(-875 3850);
DISPLAY 0.872340 (-875 3850);
DISPLAY INVISIBLE (-875 3850);
FORCEPROP 1 LAST PATH I108
J 0
(-1202 3975);
DISPLAY 0.872340 (-1202 3975);
PAINT GREEN (-1202 3975);
DISPLAY INVISIBLE (-1202 3975);
FORCEADD TAP..1
(-1200 3925);
FORCEPROP 3 LASTPIN (-1250 3925) SIG_NAME M_D_CPU1_SA_DQ<24>
J 0
(-1240 3935);
DISPLAY 0.659574 (-1240 3935);
PAINT MONO (-1240 3935);
DISPLAY INVISIBLE (-1240 3935);
FORCEPROP 1 LASTPIN (-1250 3925) BN 24
J 0
(-1262 3933);
DISPLAY 0.680851 (-1262 3933);
PAINT GREEN (-1262 3933);
FORCEPROP 2 LAST CDS_LIB standard
J 0
(-1200 3925);
DISPLAY INVISIBLE (-1200 3925);
FORCEPROP 1 LAST BODY_TYPE PLUMBING
J 0
(-1200 3975);
DISPLAY 0.872340 (-1200 3975);
PAINT GREEN (-1200 3975);
DISPLAY INVISIBLE (-1200 3975);
FORCEPROP 1 LAST HDL_TAP TRUE
J 0
(-875 3800);
DISPLAY 0.872340 (-875 3800);
DISPLAY INVISIBLE (-875 3800);
FORCEPROP 1 LAST PATH I109
J 0
(-1202 3925);
DISPLAY 0.872340 (-1202 3925);
PAINT GREEN (-1202 3925);
DISPLAY INVISIBLE (-1202 3925);
FORCEADD OFFPAGE..1
(-3775 1925);
FORCEPROP 2 LAST $XR1 104 
J 0
(-4116 1925);
DISPLAY 0.638298 (-4116 1925);
PAINT MONO (-4116 1925);
FORCEPROP 2 LAST $XR0 54 
J 0
(-3996 1925);
DISPLAY 0.638298 (-3996 1925);
PAINT MONO (-3996 1925);
FORCEPROP 2 LAST CDS_LIB standard
J 0
(-3775 1925);
PAINT MONO (-3775 1925);
DISPLAY INVISIBLE (-3775 1925);
FORCEPROP 1 LAST OFFPAGE TRUE
J 0
(-3450 1800);
DISPLAY 0.872340 (-3450 1800);
DISPLAY INVISIBLE (-3450 1800);
FORCEPROP 1 LAST COMMENT_BODY TRUE
J 0
(-3650 1825);
DISPLAY 0.872340 (-3650 1825);
PAINT GREEN (-3650 1825);
DISPLAY INVISIBLE (-3650 1825);
FORCEPROP 2 LAST PATH I11
J 0
(-3725 2000);
DISPLAY 1.021277 (-3725 2000);
DISPLAY INVISIBLE (-3725 2000);
FORCEADD TAP..1
(-1200 4025);
FORCEPROP 3 LASTPIN (-1250 4025) SIG_NAME M_D_CPU1_SA_DQ<26>
J 0
(-1240 4035);
DISPLAY 0.659574 (-1240 4035);
PAINT MONO (-1240 4035);
DISPLAY INVISIBLE (-1240 4035);
FORCEPROP 1 LASTPIN (-1250 4025) BN 26
J 0
(-1262 4033);
DISPLAY 0.680851 (-1262 4033);
PAINT GREEN (-1262 4033);
FORCEPROP 2 LAST CDS_LIB standard
J 0
(-1200 4025);
DISPLAY INVISIBLE (-1200 4025);
FORCEPROP 1 LAST BODY_TYPE PLUMBING
J 0
(-1200 4075);
DISPLAY 0.872340 (-1200 4075);
PAINT GREEN (-1200 4075);
DISPLAY INVISIBLE (-1200 4075);
FORCEPROP 1 LAST HDL_TAP TRUE
J 0
(-875 3900);
DISPLAY 0.872340 (-875 3900);
DISPLAY INVISIBLE (-875 3900);
FORCEPROP 1 LAST PATH I110
J 0
(-1202 4025);
DISPLAY 0.872340 (-1202 4025);
PAINT GREEN (-1202 4025);
DISPLAY INVISIBLE (-1202 4025);
FORCEADD TAP..1
(-1200 4075);
FORCEPROP 3 LASTPIN (-1250 4075) SIG_NAME M_D_CPU1_SA_DQ<27>
J 0
(-1240 4085);
DISPLAY 0.659574 (-1240 4085);
PAINT MONO (-1240 4085);
DISPLAY INVISIBLE (-1240 4085);
FORCEPROP 1 LASTPIN (-1250 4075) BN 27
J 0
(-1262 4083);
DISPLAY 0.680851 (-1262 4083);
PAINT GREEN (-1262 4083);
FORCEPROP 2 LAST CDS_LIB standard
J 0
(-1200 4075);
DISPLAY INVISIBLE (-1200 4075);
FORCEPROP 1 LAST BODY_TYPE PLUMBING
J 0
(-1200 4125);
DISPLAY 0.872340 (-1200 4125);
PAINT GREEN (-1200 4125);
DISPLAY INVISIBLE (-1200 4125);
FORCEPROP 1 LAST HDL_TAP TRUE
J 0
(-875 3950);
DISPLAY 0.872340 (-875 3950);
DISPLAY INVISIBLE (-875 3950);
FORCEPROP 1 LAST PATH I111
J 0
(-1202 4075);
DISPLAY 0.872340 (-1202 4075);
PAINT GREEN (-1202 4075);
DISPLAY INVISIBLE (-1202 4075);
FORCEADD TAP..1
(-1200 4125);
FORCEPROP 3 LASTPIN (-1250 4125) SIG_NAME M_D_CPU1_SA_DQ<28>
J 0
(-1240 4135);
DISPLAY 0.659574 (-1240 4135);
PAINT MONO (-1240 4135);
DISPLAY INVISIBLE (-1240 4135);
FORCEPROP 1 LASTPIN (-1250 4125) BN 28
J 0
(-1262 4133);
DISPLAY 0.680851 (-1262 4133);
PAINT GREEN (-1262 4133);
FORCEPROP 2 LAST CDS_LIB standard
J 0
(-1200 4125);
DISPLAY INVISIBLE (-1200 4125);
FORCEPROP 1 LAST BODY_TYPE PLUMBING
J 0
(-1200 4175);
DISPLAY 0.872340 (-1200 4175);
PAINT GREEN (-1200 4175);
DISPLAY INVISIBLE (-1200 4175);
FORCEPROP 1 LAST HDL_TAP TRUE
J 0
(-875 4000);
DISPLAY 0.872340 (-875 4000);
DISPLAY INVISIBLE (-875 4000);
FORCEPROP 1 LAST PATH I112
J 0
(-1202 4125);
DISPLAY 0.872340 (-1202 4125);
PAINT GREEN (-1202 4125);
DISPLAY INVISIBLE (-1202 4125);
FORCEADD OFFPAGE..1
(-3775 4300);
FORCEPROP 2 LAST $XR1 104 
J 0
(-4116 4300);
DISPLAY 0.638298 (-4116 4300);
PAINT MONO (-4116 4300);
FORCEPROP 2 LAST $XR0 54 
J 0
(-3996 4300);
DISPLAY 0.638298 (-3996 4300);
PAINT MONO (-3996 4300);
FORCEPROP 2 LAST CDS_LIB standard
J 0
(-3775 4300);
PAINT MONO (-3775 4300);
DISPLAY INVISIBLE (-3775 4300);
FORCEPROP 1 LAST OFFPAGE TRUE
J 0
(-3450 4175);
DISPLAY 0.872340 (-3450 4175);
DISPLAY INVISIBLE (-3450 4175);
FORCEPROP 1 LAST COMMENT_BODY TRUE
J 0
(-3650 4200);
DISPLAY 0.872340 (-3650 4200);
PAINT GREEN (-3650 4200);
DISPLAY INVISIBLE (-3650 4200);
FORCEPROP 2 LAST PATH I113
J 0
(-3725 4375);
DISPLAY 1.021277 (-3725 4375);
DISPLAY INVISIBLE (-3725 4375);
FORCEADD TAP..1
R 2
(-2850 4225);
FORCEPROP 3 LASTPIN (-2800 4225) SIG_NAME M_D_CPU1_SA_CA<5>
J 0
(-2790 4235);
DISPLAY 0.659574 (-2790 4235);
PAINT MONO (-2790 4235);
DISPLAY INVISIBLE (-2790 4235);
FORCEPROP 1 LASTPIN (-2800 4225) BN 5
J 2
(-2788 4233);
DISPLAY 0.680851 (-2788 4233);
PAINT GREEN (-2788 4233);
FORCEPROP 2 LAST CDS_LIB standard
J 0
(-2850 4225);
DISPLAY INVISIBLE (-2850 4225);
FORCEPROP 1 LAST BODY_TYPE PLUMBING
J 2
(-2850 4275);
DISPLAY 0.872340 (-2850 4275);
PAINT GREEN (-2850 4275);
DISPLAY INVISIBLE (-2850 4275);
FORCEPROP 1 LAST HDL_TAP TRUE
J 2
(-3175 4100);
DISPLAY 0.872340 (-3175 4100);
DISPLAY INVISIBLE (-3175 4100);
FORCEPROP 1 LAST PATH I114
J 2
(-2848 4225);
DISPLAY 0.872340 (-2848 4225);
PAINT GREEN (-2848 4225);
DISPLAY INVISIBLE (-2848 4225);
FORCEADD TAP..1
R 2
(-2850 4175);
FORCEPROP 3 LASTPIN (-2800 4175) SIG_NAME M_D_CPU1_SA_CA<4>
J 0
(-2790 4185);
DISPLAY 0.659574 (-2790 4185);
PAINT MONO (-2790 4185);
DISPLAY INVISIBLE (-2790 4185);
FORCEPROP 1 LASTPIN (-2800 4175) BN 4
J 2
(-2788 4183);
DISPLAY 0.680851 (-2788 4183);
PAINT GREEN (-2788 4183);
FORCEPROP 2 LAST CDS_LIB standard
J 0
(-2850 4175);
DISPLAY INVISIBLE (-2850 4175);
FORCEPROP 1 LAST BODY_TYPE PLUMBING
J 2
(-2850 4225);
DISPLAY 0.872340 (-2850 4225);
PAINT GREEN (-2850 4225);
DISPLAY INVISIBLE (-2850 4225);
FORCEPROP 1 LAST HDL_TAP TRUE
J 2
(-3175 4050);
DISPLAY 0.872340 (-3175 4050);
DISPLAY INVISIBLE (-3175 4050);
FORCEPROP 1 LAST PATH I115
J 2
(-2848 4175);
DISPLAY 0.872340 (-2848 4175);
PAINT GREEN (-2848 4175);
DISPLAY INVISIBLE (-2848 4175);
FORCEADD TAP..1
R 2
(-2850 4275);
FORCEPROP 3 LASTPIN (-2800 4275) SIG_NAME M_D_CPU1_SA_CA<6>
J 0
(-2790 4285);
DISPLAY 0.659574 (-2790 4285);
PAINT MONO (-2790 4285);
DISPLAY INVISIBLE (-2790 4285);
FORCEPROP 1 LASTPIN (-2800 4275) BN 6
J 2
(-2788 4283);
DISPLAY 0.680851 (-2788 4283);
PAINT GREEN (-2788 4283);
FORCEPROP 2 LAST CDS_LIB standard
J 0
(-2850 4275);
DISPLAY INVISIBLE (-2850 4275);
FORCEPROP 1 LAST BODY_TYPE PLUMBING
J 2
(-2850 4325);
DISPLAY 0.872340 (-2850 4325);
PAINT GREEN (-2850 4325);
DISPLAY INVISIBLE (-2850 4325);
FORCEPROP 1 LAST HDL_TAP TRUE
J 2
(-3175 4150);
DISPLAY 0.872340 (-3175 4150);
DISPLAY INVISIBLE (-3175 4150);
FORCEPROP 1 LAST PATH I116
J 2
(-2848 4275);
DISPLAY 0.872340 (-2848 4275);
PAINT GREEN (-2848 4275);
DISPLAY INVISIBLE (-2848 4275);
FORCEADD TAP..1
(-1200 4275);
FORCEPROP 3 LASTPIN (-1250 4275) SIG_NAME M_D_CPU1_SA_DQ<31>
J 0
(-1240 4285);
DISPLAY 0.659574 (-1240 4285);
PAINT MONO (-1240 4285);
DISPLAY INVISIBLE (-1240 4285);
FORCEPROP 1 LASTPIN (-1250 4275) BN 31
J 0
(-1262 4283);
DISPLAY 0.680851 (-1262 4283);
PAINT GREEN (-1262 4283);
FORCEPROP 2 LAST CDS_LIB standard
J 0
(-1200 4275);
DISPLAY INVISIBLE (-1200 4275);
FORCEPROP 1 LAST BODY_TYPE PLUMBING
J 0
(-1200 4325);
DISPLAY 0.872340 (-1200 4325);
PAINT GREEN (-1200 4325);
DISPLAY INVISIBLE (-1200 4325);
FORCEPROP 1 LAST HDL_TAP TRUE
J 0
(-875 4150);
DISPLAY 0.872340 (-875 4150);
DISPLAY INVISIBLE (-875 4150);
FORCEPROP 1 LAST PATH I117
J 0
(-1202 4275);
DISPLAY 0.872340 (-1202 4275);
PAINT GREEN (-1202 4275);
DISPLAY INVISIBLE (-1202 4275);
FORCEADD TAP..1
(-1200 4225);
FORCEPROP 3 LASTPIN (-1250 4225) SIG_NAME M_D_CPU1_SA_DQ<30>
J 0
(-1240 4235);
DISPLAY 0.659574 (-1240 4235);
PAINT MONO (-1240 4235);
DISPLAY INVISIBLE (-1240 4235);
FORCEPROP 1 LASTPIN (-1250 4225) BN 30
J 0
(-1262 4233);
DISPLAY 0.680851 (-1262 4233);
PAINT GREEN (-1262 4233);
FORCEPROP 2 LAST CDS_LIB standard
J 0
(-1200 4225);
DISPLAY INVISIBLE (-1200 4225);
FORCEPROP 1 LAST BODY_TYPE PLUMBING
J 0
(-1200 4275);
DISPLAY 0.872340 (-1200 4275);
PAINT GREEN (-1200 4275);
DISPLAY INVISIBLE (-1200 4275);
FORCEPROP 1 LAST HDL_TAP TRUE
J 0
(-875 4100);
DISPLAY 0.872340 (-875 4100);
DISPLAY INVISIBLE (-875 4100);
FORCEPROP 1 LAST PATH I118
J 0
(-1202 4225);
DISPLAY 0.872340 (-1202 4225);
PAINT GREEN (-1202 4225);
DISPLAY INVISIBLE (-1202 4225);
FORCEADD TAP..1
(-1200 4175);
FORCEPROP 3 LASTPIN (-1250 4175) SIG_NAME M_D_CPU1_SA_DQ<29>
J 0
(-1240 4185);
DISPLAY 0.659574 (-1240 4185);
PAINT MONO (-1240 4185);
DISPLAY INVISIBLE (-1240 4185);
FORCEPROP 1 LASTPIN (-1250 4175) BN 29
J 0
(-1262 4183);
DISPLAY 0.680851 (-1262 4183);
PAINT GREEN (-1262 4183);
FORCEPROP 2 LAST CDS_LIB standard
J 0
(-1200 4175);
DISPLAY INVISIBLE (-1200 4175);
FORCEPROP 1 LAST BODY_TYPE PLUMBING
J 0
(-1200 4225);
DISPLAY 0.872340 (-1200 4225);
PAINT GREEN (-1200 4225);
DISPLAY INVISIBLE (-1200 4225);
FORCEPROP 1 LAST HDL_TAP TRUE
J 0
(-875 4050);
DISPLAY 0.872340 (-875 4050);
DISPLAY INVISIBLE (-875 4050);
FORCEPROP 1 LAST PATH I119
J 0
(-1202 4175);
DISPLAY 0.872340 (-1202 4175);
PAINT GREEN (-1202 4175);
DISPLAY INVISIBLE (-1202 4175);
FORCEADD VCC_CORE..1
(-3675 2150);
FORCEPROP 3 LASTPIN (-3675 2100) SIG_NAME P3V3_AUX\g
J 0
(-3665 2110);
DISPLAY 0.659574 (-3665 2110);
PAINT MONO (-3665 2110);
DISPLAY INVISIBLE (-3665 2110);
FORCEPROP 1 LAST HDL_POWER P3V3_AUX
J 1
(-3675 2200);
DISPLAY 1.148936 (-3675 2200);
PAINT GREEN (-3675 2200);
FORCEPROP 2 LAST CDS_LIB logical_power
J 0
(-3675 2150);
PAINT MONO (-3675 2150);
DISPLAY INVISIBLE (-3675 2150);
FORCEPROP 1 LAST PATH I12
J 0
(-3625 2175);
DISPLAY 0.872340 (-3625 2175);
PAINT AQUA (-3625 2175);
DISPLAY INVISIBLE (-3625 2175);
FORCEADD UNIVERSAL_GND..1
(525 25);
FORCEPROP 3 LASTPIN (525 75) SIG_NAME GND\g
J 0
(535 85);
DISPLAY 0.659574 (535 85);
PAINT MONO (535 85);
DISPLAY INVISIBLE (535 85);
FORCEPROP 1 LAST PATH I120
J 0
(600 25);
DISPLAY 0.872340 (600 25);
PAINT AQUA (600 25);
DISPLAY INVISIBLE (600 25);
FORCEPROP 1 LAST HDL_POWER GND
J 1
(550 -50);
DISPLAY 0.872340 (550 -50);
PAINT GREEN (550 -50);
DISPLAY INVISIBLE (550 -50);
FORCEPROP 2 LAST CDS_LIB logical_power
J 0
(525 25);
PAINT MONO (525 25);
DISPLAY INVISIBLE (525 25);
FORCEADD UNIVERSAL_GND..1
(2150 25);
FORCEPROP 3 LASTPIN (2150 75) SIG_NAME GND\g
J 0
(2160 85);
DISPLAY 0.659574 (2160 85);
PAINT MONO (2160 85);
DISPLAY INVISIBLE (2160 85);
FORCEPROP 1 LAST PATH I121
J 0
(2225 25);
DISPLAY 0.872340 (2225 25);
PAINT AQUA (2225 25);
DISPLAY INVISIBLE (2225 25);
FORCEPROP 1 LAST HDL_POWER GND
J 1
(2175 -50);
DISPLAY 0.872340 (2175 -50);
PAINT GREEN (2175 -50);
DISPLAY INVISIBLE (2175 -50);
FORCEPROP 2 LAST CDS_LIB logical_power
J 0
(2150 25);
PAINT MONO (2150 25);
DISPLAY INVISIBLE (2150 25);
FORCEADD VCC_CORE..1
(525 725);
FORCEPROP 3 LASTPIN (525 675) SIG_NAME P3V3_AUX\g
J 0
(535 685);
DISPLAY 0.659574 (535 685);
PAINT MONO (535 685);
DISPLAY INVISIBLE (535 685);
FORCEPROP 1 LAST HDL_POWER P3V3_AUX
J 1
(525 775);
DISPLAY 1.148936 (525 775);
PAINT GREEN (525 775);
FORCEPROP 2 LAST CDS_LIB logical_power
J 0
(525 725);
PAINT MONO (525 725);
DISPLAY INVISIBLE (525 725);
FORCEPROP 1 LAST PATH I122
J 0
(575 750);
DISPLAY 0.872340 (575 750);
PAINT AQUA (575 750);
DISPLAY INVISIBLE (575 750);
FORCEADD Q_CAP..1
(525 400);
FORCEPROP 1 LAST PART_NUMBER CH5221MEB00
J 0
(575 250);
DISPLAY 0.978723 (575 250);
DISPLAY INVISIBLE (575 250);
FORCEPROP 1 LAST TOLERANCE 20%
J 0
(575 350);
DISPLAY 0.978723 (575 350);
FORCEPROP 1 LAST VOLTAGE 6.3V
J 0
(575 400);
DISPLAY 0.978723 (575 400);
FORCEPROP 1 LAST MATERIAL X6S
J 0
(575 300);
DISPLAY 0.978723 (575 300);
FORCEPROP 1 LAST PACK_TYPE C0402
J 0
(575 200);
DISPLAY 0.978723 (575 200);
FORCEPROP 1 LAST VALUE 2.2UF
J 0
(575 450);
DISPLAY 0.978723 (575 450);
FORCEPROP 1 LAST $LOCATION C96
J 0
(575 500);
DISPLAY 0.978723 (575 500);
FORCEPROP 1 LASTPIN (525 500) $PN 1
J 0
(535 480);
DISPLAY 0.787234 (535 480);
FORCEPROP 1 LASTPIN (525 300) $PN 2
J 0
(535 280);
DISPLAY 0.787234 (535 280);
FORCEPROP 2 LAST CDS_LIB pure_quanta
J 0
(525 400);
PAINT MONO (525 400);
DISPLAY INVISIBLE (525 400);
FORCEPROP 1 LAST PATH I123
J 0
(575 550);
DISPLAY 0.978723 (575 550);
PAINT WHITE (575 550);
DISPLAY INVISIBLE (575 550);
FORCEPROP 1 LAST $LOCATION C96
J 0
(575 600);
DISPLAY 1.021277 (575 600);
DISPLAY INVISIBLE (575 600);
FORCEPROP 2 LAST CDS_LOCATION C96
J 0
(575 600);
DISPLAY 1.021277 (575 600);
DISPLAY INVISIBLE (575 600);
FORCEPROP 2 LAST $SEC 1
J 0
(575 600);
DISPLAY 0.680851 (575 600);
PAINT MONO (575 600);
DISPLAY INVISIBLE (575 600);
FORCEPROP 2 LAST CDS_SEC 1
J 0
(575 600);
DISPLAY 1.021277 (575 600);
DISPLAY INVISIBLE (575 600);
FORCEADD Q_CAP..1
(1525 400);
FORCEPROP 1 LAST PART_NUMBER CH6103KEA00
J 0
(1575 250);
DISPLAY 0.978723 (1575 250);
DISPLAY INVISIBLE (1575 250);
FORCEPROP 1 LAST VOLTAGE 16V
J 0
(1575 400);
DISPLAY 0.978723 (1575 400);
FORCEPROP 1 LAST VALUE 10UF
J 0
(1575 450);
DISPLAY 0.978723 (1575 450);
FORCEPROP 1 LAST TOLERANCE 10%
J 0
(1575 350);
DISPLAY 0.978723 (1575 350);
FORCEPROP 1 LAST PACK_TYPE C0805
J 0
(1575 200);
DISPLAY 0.978723 (1575 200);
FORCEPROP 1 LAST MATERIAL X6S
J 0
(1575 300);
DISPLAY 0.978723 (1575 300);
FORCEPROP 1 LAST $LOCATION C97
J 0
(1575 500);
DISPLAY 0.978723 (1575 500);
FORCEPROP 1 LASTPIN (1525 500) $PN 1
J 0
(1535 480);
DISPLAY 0.787234 (1535 480);
FORCEPROP 1 LASTPIN (1525 300) $PN 2
J 0
(1535 280);
DISPLAY 0.787234 (1535 280);
FORCEPROP 2 LAST CDS_LIB pure_quanta
J 0
(1525 400);
PAINT MONO (1525 400);
DISPLAY INVISIBLE (1525 400);
FORCEPROP 1 LAST PATH I124
J 0
(1575 550);
DISPLAY 0.978723 (1575 550);
PAINT WHITE (1575 550);
DISPLAY INVISIBLE (1575 550);
FORCEPROP 1 LAST $LOCATION C97
J 0
(1575 600);
DISPLAY 1.021277 (1575 600);
DISPLAY INVISIBLE (1575 600);
FORCEPROP 2 LAST CDS_LOCATION C97
J 0
(1575 600);
DISPLAY 1.021277 (1575 600);
DISPLAY INVISIBLE (1575 600);
FORCEPROP 2 LAST $SEC 1
J 0
(1575 600);
DISPLAY 0.680851 (1575 600);
PAINT MONO (1575 600);
DISPLAY INVISIBLE (1575 600);
FORCEPROP 2 LAST CDS_SEC 1
J 0
(1575 600);
DISPLAY 1.021277 (1575 600);
DISPLAY INVISIBLE (1575 600);
FORCEADD VCC_CORE..1
(1525 725);
FORCEPROP 3 LASTPIN (1525 675) SIG_NAME P12V_S3_AUX_CPU1_NVDIMM\g
J 0
(1535 685);
DISPLAY 0.659574 (1535 685);
PAINT MONO (1535 685);
DISPLAY INVISIBLE (1535 685);
FORCEPROP 1 LAST HDL_POWER P12V_S3_AUX_CPU1_NVDIMM
J 1
(1525 775);
DISPLAY 1.148936 (1525 775);
PAINT GREEN (1525 775);
FORCEPROP 2 LAST CDS_LIB logical_power
J 0
(1525 725);
PAINT MONO (1525 725);
DISPLAY INVISIBLE (1525 725);
FORCEPROP 1 LAST PATH I125
J 0
(1575 750);
DISPLAY 0.872340 (1575 750);
PAINT AQUA (1575 750);
DISPLAY INVISIBLE (1575 750);
FORCEADD OFFPAGE..3
(-375 2650);
FORCEPROP 2 LAST $XR1 104 
J 0
(-71 2650);
DISPLAY 0.638298 (-71 2650);
PAINT MONO (-71 2650);
FORCEPROP 2 LAST $XR0 54 
J 0
(-161 2650);
DISPLAY 0.638298 (-161 2650);
PAINT MONO (-161 2650);
FORCEPROP 2 LAST CDS_LIB standard
J 2
(-375 2650);
DISPLAY INVISIBLE (-375 2650);
FORCEPROP 1 LAST OFFPAGE TRUE
J 0
(-50 2525);
DISPLAY 0.872340 (-50 2525);
DISPLAY INVISIBLE (-50 2525);
FORCEPROP 1 LAST COMMENT_BODY TRUE
J 0
(-425 2550);
DISPLAY 0.872340 (-425 2550);
PAINT GREEN (-425 2550);
DISPLAY INVISIBLE (-425 2550);
FORCEPROP 2 LAST PATH I126
J 0
(-175 2725);
DISPLAY 1.021277 (-175 2725);
DISPLAY INVISIBLE (-175 2725);
FORCEADD TAP..1
(1550 2325);
FORCEPROP 3 LASTPIN (1500 2325) SIG_NAME M_D_CPU1_SB_DQS_DP<0>
J 0
(1510 2335);
DISPLAY 0.659574 (1510 2335);
PAINT MONO (1510 2335);
DISPLAY INVISIBLE (1510 2335);
FORCEPROP 1 LASTPIN (1500 2325) BN 0
J 0
(1488 2333);
DISPLAY 0.680851 (1488 2333);
PAINT GREEN (1488 2333);
FORCEPROP 2 LAST CDS_LIB standard
J 0
(1550 2325);
PAINT MONO (1550 2325);
DISPLAY INVISIBLE (1550 2325);
FORCEPROP 1 LAST BODY_TYPE PLUMBING
J 0
(1550 2375);
DISPLAY 0.872340 (1550 2375);
PAINT GREEN (1550 2375);
DISPLAY INVISIBLE (1550 2375);
FORCEPROP 1 LAST HDL_TAP TRUE
J 0
(1875 2200);
DISPLAY 0.872340 (1875 2200);
DISPLAY INVISIBLE (1875 2200);
FORCEPROP 1 LAST PATH I128
J 0
(1548 2325);
DISPLAY 0.872340 (1548 2325);
PAINT GREEN (1548 2325);
DISPLAY INVISIBLE (1548 2325);
FORCEADD TAP..1
(1550 2425);
FORCEPROP 3 LASTPIN (1500 2425) SIG_NAME M_D_CPU1_SB_DQS_DP<1>
J 0
(1510 2435);
DISPLAY 0.659574 (1510 2435);
PAINT MONO (1510 2435);
DISPLAY INVISIBLE (1510 2435);
FORCEPROP 1 LASTPIN (1500 2425) BN 1
J 0
(1488 2433);
DISPLAY 0.680851 (1488 2433);
PAINT GREEN (1488 2433);
FORCEPROP 2 LAST CDS_LIB standard
J 0
(1550 2425);
DISPLAY INVISIBLE (1550 2425);
FORCEPROP 1 LAST BODY_TYPE PLUMBING
J 0
(1550 2475);
DISPLAY 0.872340 (1550 2475);
PAINT GREEN (1550 2475);
DISPLAY INVISIBLE (1550 2475);
FORCEPROP 1 LAST HDL_TAP TRUE
J 0
(1875 2300);
DISPLAY 0.872340 (1875 2300);
DISPLAY INVISIBLE (1875 2300);
FORCEPROP 1 LAST PATH I129
J 0
(1548 2425);
DISPLAY 0.872340 (1548 2425);
PAINT GREEN (1548 2425);
DISPLAY INVISIBLE (1548 2425);
FORCEADD TAP..1
(1550 2625);
FORCEPROP 3 LASTPIN (1500 2625) SIG_NAME M_D_CPU1_SB_DQS_DP<3>
J 0
(1510 2635);
DISPLAY 0.659574 (1510 2635);
PAINT MONO (1510 2635);
DISPLAY INVISIBLE (1510 2635);
FORCEPROP 1 LASTPIN (1500 2625) BN 3
J 0
(1488 2633);
DISPLAY 0.680851 (1488 2633);
PAINT GREEN (1488 2633);
FORCEPROP 2 LAST CDS_LIB standard
J 0
(1550 2625);
PAINT MONO (1550 2625);
DISPLAY INVISIBLE (1550 2625);
FORCEPROP 1 LAST BODY_TYPE PLUMBING
J 0
(1550 2675);
DISPLAY 0.872340 (1550 2675);
PAINT GREEN (1550 2675);
DISPLAY INVISIBLE (1550 2675);
FORCEPROP 1 LAST HDL_TAP TRUE
J 0
(1875 2500);
DISPLAY 0.872340 (1875 2500);
DISPLAY INVISIBLE (1875 2500);
FORCEPROP 1 LAST PATH I130
J 0
(1548 2625);
DISPLAY 0.872340 (1548 2625);
PAINT GREEN (1548 2625);
DISPLAY INVISIBLE (1548 2625);
FORCEADD TAP..1
(1550 2525);
FORCEPROP 3 LASTPIN (1500 2525) SIG_NAME M_D_CPU1_SB_DQS_DP<2>
J 0
(1510 2535);
DISPLAY 0.659574 (1510 2535);
PAINT MONO (1510 2535);
DISPLAY INVISIBLE (1510 2535);
FORCEPROP 1 LASTPIN (1500 2525) BN 2
J 0
(1488 2533);
DISPLAY 0.680851 (1488 2533);
PAINT GREEN (1488 2533);
FORCEPROP 2 LAST CDS_LIB standard
J 0
(1550 2525);
DISPLAY INVISIBLE (1550 2525);
FORCEPROP 1 LAST BODY_TYPE PLUMBING
J 0
(1550 2575);
DISPLAY 0.872340 (1550 2575);
PAINT GREEN (1550 2575);
DISPLAY INVISIBLE (1550 2575);
FORCEPROP 1 LAST HDL_TAP TRUE
J 0
(1875 2400);
DISPLAY 0.872340 (1875 2400);
DISPLAY INVISIBLE (1875 2400);
FORCEPROP 1 LAST PATH I131
J 0
(1548 2525);
DISPLAY 0.872340 (1548 2525);
PAINT GREEN (1548 2525);
DISPLAY INVISIBLE (1548 2525);
FORCEADD TAP..1
(1550 2725);
FORCEPROP 3 LASTPIN (1500 2725) SIG_NAME M_D_CPU1_SB_DQS_DP<4>
J 0
(1510 2735);
DISPLAY 0.659574 (1510 2735);
PAINT MONO (1510 2735);
DISPLAY INVISIBLE (1510 2735);
FORCEPROP 1 LASTPIN (1500 2725) BN 4
J 0
(1488 2733);
DISPLAY 0.680851 (1488 2733);
PAINT GREEN (1488 2733);
FORCEPROP 2 LAST CDS_LIB standard
J 0
(1550 2725);
PAINT MONO (1550 2725);
DISPLAY INVISIBLE (1550 2725);
FORCEPROP 1 LAST BODY_TYPE PLUMBING
J 0
(1550 2775);
DISPLAY 0.872340 (1550 2775);
PAINT GREEN (1550 2775);
DISPLAY INVISIBLE (1550 2775);
FORCEPROP 1 LAST HDL_TAP TRUE
J 0
(1875 2600);
DISPLAY 0.872340 (1875 2600);
DISPLAY INVISIBLE (1875 2600);
FORCEPROP 1 LAST PATH I132
J 0
(1548 2725);
DISPLAY 0.872340 (1548 2725);
PAINT GREEN (1548 2725);
DISPLAY INVISIBLE (1548 2725);
FORCEADD TAP..1
(1550 2825);
FORCEPROP 3 LASTPIN (1500 2825) SIG_NAME M_D_CPU1_SB_DQS_DP<5>
J 0
(1510 2835);
DISPLAY 0.659574 (1510 2835);
PAINT MONO (1510 2835);
DISPLAY INVISIBLE (1510 2835);
FORCEPROP 1 LASTPIN (1500 2825) BN 5
J 0
(1488 2833);
DISPLAY 0.680851 (1488 2833);
PAINT GREEN (1488 2833);
FORCEPROP 2 LAST CDS_LIB standard
J 0
(1550 2825);
DISPLAY INVISIBLE (1550 2825);
FORCEPROP 1 LAST BODY_TYPE PLUMBING
J 0
(1550 2875);
DISPLAY 0.872340 (1550 2875);
PAINT GREEN (1550 2875);
DISPLAY INVISIBLE (1550 2875);
FORCEPROP 1 LAST HDL_TAP TRUE
J 0
(1875 2700);
DISPLAY 0.872340 (1875 2700);
DISPLAY INVISIBLE (1875 2700);
FORCEPROP 1 LAST PATH I133
J 0
(1548 2825);
DISPLAY 0.872340 (1548 2825);
PAINT GREEN (1548 2825);
DISPLAY INVISIBLE (1548 2825);
FORCEADD TAP..1
(1550 2925);
FORCEPROP 3 LASTPIN (1500 2925) SIG_NAME M_D_CPU1_SB_DQS_DP<6>
J 0
(1510 2935);
DISPLAY 0.659574 (1510 2935);
PAINT MONO (1510 2935);
DISPLAY INVISIBLE (1510 2935);
FORCEPROP 1 LASTPIN (1500 2925) BN 6
J 0
(1488 2933);
DISPLAY 0.680851 (1488 2933);
PAINT GREEN (1488 2933);
FORCEPROP 2 LAST CDS_LIB standard
J 0
(1550 2925);
DISPLAY INVISIBLE (1550 2925);
FORCEPROP 1 LAST BODY_TYPE PLUMBING
J 0
(1550 2975);
DISPLAY 0.872340 (1550 2975);
PAINT GREEN (1550 2975);
DISPLAY INVISIBLE (1550 2975);
FORCEPROP 1 LAST HDL_TAP TRUE
J 0
(1875 2800);
DISPLAY 0.872340 (1875 2800);
DISPLAY INVISIBLE (1875 2800);
FORCEPROP 1 LAST PATH I134
J 0
(1548 2925);
DISPLAY 0.872340 (1548 2925);
PAINT GREEN (1548 2925);
DISPLAY INVISIBLE (1548 2925);
FORCEADD TAP..1
(1550 3125);
FORCEPROP 3 LASTPIN (1500 3125) SIG_NAME M_D_CPU1_SB_DQS_DP<8>
J 0
(1510 3135);
DISPLAY 0.659574 (1510 3135);
PAINT MONO (1510 3135);
DISPLAY INVISIBLE (1510 3135);
FORCEPROP 1 LASTPIN (1500 3125) BN 8
J 0
(1488 3133);
DISPLAY 0.680851 (1488 3133);
PAINT GREEN (1488 3133);
FORCEPROP 2 LAST CDS_LIB standard
J 0
(1550 3125);
DISPLAY INVISIBLE (1550 3125);
FORCEPROP 1 LAST BODY_TYPE PLUMBING
J 0
(1550 3175);
DISPLAY 0.872340 (1550 3175);
PAINT GREEN (1550 3175);
DISPLAY INVISIBLE (1550 3175);
FORCEPROP 1 LAST HDL_TAP TRUE
J 0
(1875 3000);
DISPLAY 0.872340 (1875 3000);
DISPLAY INVISIBLE (1875 3000);
FORCEPROP 1 LAST PATH I135
J 0
(1548 3125);
DISPLAY 0.872340 (1548 3125);
PAINT GREEN (1548 3125);
DISPLAY INVISIBLE (1548 3125);
FORCEADD TAP..1
(1550 3025);
FORCEPROP 3 LASTPIN (1500 3025) SIG_NAME M_D_CPU1_SB_DQS_DP<7>
J 0
(1510 3035);
DISPLAY 0.659574 (1510 3035);
PAINT MONO (1510 3035);
DISPLAY INVISIBLE (1510 3035);
FORCEPROP 1 LASTPIN (1500 3025) BN 7
J 0
(1488 3033);
DISPLAY 0.680851 (1488 3033);
PAINT GREEN (1488 3033);
FORCEPROP 2 LAST CDS_LIB standard
J 0
(1550 3025);
DISPLAY INVISIBLE (1550 3025);
FORCEPROP 1 LAST BODY_TYPE PLUMBING
J 0
(1550 3075);
DISPLAY 0.872340 (1550 3075);
PAINT GREEN (1550 3075);
DISPLAY INVISIBLE (1550 3075);
FORCEPROP 1 LAST HDL_TAP TRUE
J 0
(1875 2900);
DISPLAY 0.872340 (1875 2900);
DISPLAY INVISIBLE (1875 2900);
FORCEPROP 1 LAST PATH I136
J 0
(1548 3025);
DISPLAY 0.872340 (1548 3025);
PAINT GREEN (1548 3025);
DISPLAY INVISIBLE (1548 3025);
FORCEADD TAP..1
(1550 3375);
FORCEPROP 3 LASTPIN (1500 3375) SIG_NAME M_D_CPU1_SA_DQS_DP<0>
J 0
(1510 3385);
DISPLAY 0.659574 (1510 3385);
PAINT MONO (1510 3385);
DISPLAY INVISIBLE (1510 3385);
FORCEPROP 1 LASTPIN (1500 3375) BN 0
J 0
(1488 3383);
DISPLAY 0.680851 (1488 3383);
PAINT GREEN (1488 3383);
FORCEPROP 2 LAST CDS_LIB standard
J 0
(1550 3375);
PAINT MONO (1550 3375);
DISPLAY INVISIBLE (1550 3375);
FORCEPROP 1 LAST BODY_TYPE PLUMBING
J 0
(1550 3425);
DISPLAY 0.872340 (1550 3425);
PAINT GREEN (1550 3425);
DISPLAY INVISIBLE (1550 3425);
FORCEPROP 1 LAST HDL_TAP TRUE
J 0
(1875 3250);
DISPLAY 0.872340 (1875 3250);
DISPLAY INVISIBLE (1875 3250);
FORCEPROP 1 LAST PATH I137
J 0
(1548 3375);
DISPLAY 0.872340 (1548 3375);
PAINT GREEN (1548 3375);
DISPLAY INVISIBLE (1548 3375);
FORCEADD TAP..1
(1550 3225);
FORCEPROP 3 LASTPIN (1500 3225) SIG_NAME M_D_CPU1_SB_DQS_DP<9>
J 0
(1510 3235);
DISPLAY 0.659574 (1510 3235);
PAINT MONO (1510 3235);
DISPLAY INVISIBLE (1510 3235);
FORCEPROP 1 LASTPIN (1500 3225) BN 9
J 0
(1488 3233);
DISPLAY 0.680851 (1488 3233);
PAINT GREEN (1488 3233);
FORCEPROP 2 LAST CDS_LIB standard
J 0
(1550 3225);
DISPLAY INVISIBLE (1550 3225);
FORCEPROP 1 LAST BODY_TYPE PLUMBING
J 0
(1550 3275);
DISPLAY 0.872340 (1550 3275);
PAINT GREEN (1550 3275);
DISPLAY INVISIBLE (1550 3275);
FORCEPROP 1 LAST HDL_TAP TRUE
J 0
(1875 3100);
DISPLAY 0.872340 (1875 3100);
DISPLAY INVISIBLE (1875 3100);
FORCEPROP 1 LAST PATH I138
J 0
(1548 3225);
DISPLAY 0.872340 (1548 3225);
PAINT GREEN (1548 3225);
DISPLAY INVISIBLE (1548 3225);
FORCEADD TAP..1
(1550 3475);
FORCEPROP 3 LASTPIN (1500 3475) SIG_NAME M_D_CPU1_SA_DQS_DP<1>
J 0
(1510 3485);
DISPLAY 0.659574 (1510 3485);
PAINT MONO (1510 3485);
DISPLAY INVISIBLE (1510 3485);
FORCEPROP 1 LASTPIN (1500 3475) BN 1
J 0
(1488 3483);
DISPLAY 0.680851 (1488 3483);
PAINT GREEN (1488 3483);
FORCEPROP 2 LAST CDS_LIB standard
J 0
(1550 3475);
DISPLAY INVISIBLE (1550 3475);
FORCEPROP 1 LAST BODY_TYPE PLUMBING
J 0
(1550 3525);
DISPLAY 0.872340 (1550 3525);
PAINT GREEN (1550 3525);
DISPLAY INVISIBLE (1550 3525);
FORCEPROP 1 LAST HDL_TAP TRUE
J 0
(1875 3350);
DISPLAY 0.872340 (1875 3350);
DISPLAY INVISIBLE (1875 3350);
FORCEPROP 1 LAST PATH I139
J 0
(1548 3475);
DISPLAY 0.872340 (1548 3475);
PAINT GREEN (1548 3475);
DISPLAY INVISIBLE (1548 3475);
FORCEADD TAP..1
R 2
(-2850 2075);
FORCEPROP 3 LASTPIN (-2800 2075) SIG_NAME M_D_CPU1_SB_CB<0>
J 0
(-2790 2085);
DISPLAY 0.659574 (-2790 2085);
PAINT MONO (-2790 2085);
DISPLAY INVISIBLE (-2790 2085);
FORCEPROP 1 LASTPIN (-2800 2075) BN 0
J 2
(-2788 2083);
DISPLAY 0.680851 (-2788 2083);
PAINT GREEN (-2788 2083);
FORCEPROP 2 LAST CDS_LIB standard
J 0
(-2850 2075);
PAINT MONO (-2850 2075);
DISPLAY INVISIBLE (-2850 2075);
FORCEPROP 1 LAST BODY_TYPE PLUMBING
J 2
(-2850 2125);
DISPLAY 0.872340 (-2850 2125);
PAINT GREEN (-2850 2125);
DISPLAY INVISIBLE (-2850 2125);
FORCEPROP 1 LAST HDL_TAP TRUE
J 2
(-3175 1950);
DISPLAY 0.872340 (-3175 1950);
DISPLAY INVISIBLE (-3175 1950);
FORCEPROP 1 LAST PATH I14
J 2
(-2848 2075);
DISPLAY 0.872340 (-2848 2075);
PAINT GREEN (-2848 2075);
DISPLAY INVISIBLE (-2848 2075);
FORCEADD TAP..1
(1550 3575);
FORCEPROP 3 LASTPIN (1500 3575) SIG_NAME M_D_CPU1_SA_DQS_DP<2>
J 0
(1510 3585);
DISPLAY 0.659574 (1510 3585);
PAINT MONO (1510 3585);
DISPLAY INVISIBLE (1510 3585);
FORCEPROP 1 LASTPIN (1500 3575) BN 2
J 0
(1488 3583);
DISPLAY 0.680851 (1488 3583);
PAINT GREEN (1488 3583);
FORCEPROP 2 LAST CDS_LIB standard
J 0
(1550 3575);
DISPLAY INVISIBLE (1550 3575);
FORCEPROP 1 LAST BODY_TYPE PLUMBING
J 0
(1550 3625);
DISPLAY 0.872340 (1550 3625);
PAINT GREEN (1550 3625);
DISPLAY INVISIBLE (1550 3625);
FORCEPROP 1 LAST HDL_TAP TRUE
J 0
(1875 3450);
DISPLAY 0.872340 (1875 3450);
DISPLAY INVISIBLE (1875 3450);
FORCEPROP 1 LAST PATH I140
J 0
(1548 3575);
DISPLAY 0.872340 (1548 3575);
PAINT GREEN (1548 3575);
DISPLAY INVISIBLE (1548 3575);
FORCEADD TAP..1
(1550 3675);
FORCEPROP 3 LASTPIN (1500 3675) SIG_NAME M_D_CPU1_SA_DQS_DP<3>
J 0
(1510 3685);
DISPLAY 0.659574 (1510 3685);
PAINT MONO (1510 3685);
DISPLAY INVISIBLE (1510 3685);
FORCEPROP 1 LASTPIN (1500 3675) BN 3
J 0
(1488 3683);
DISPLAY 0.680851 (1488 3683);
PAINT GREEN (1488 3683);
FORCEPROP 2 LAST CDS_LIB standard
J 0
(1550 3675);
PAINT MONO (1550 3675);
DISPLAY INVISIBLE (1550 3675);
FORCEPROP 1 LAST BODY_TYPE PLUMBING
J 0
(1550 3725);
DISPLAY 0.872340 (1550 3725);
PAINT GREEN (1550 3725);
DISPLAY INVISIBLE (1550 3725);
FORCEPROP 1 LAST HDL_TAP TRUE
J 0
(1875 3550);
DISPLAY 0.872340 (1875 3550);
DISPLAY INVISIBLE (1875 3550);
FORCEPROP 1 LAST PATH I141
J 0
(1548 3675);
DISPLAY 0.872340 (1548 3675);
PAINT GREEN (1548 3675);
DISPLAY INVISIBLE (1548 3675);
FORCEADD TAP..1
(1550 3775);
FORCEPROP 3 LASTPIN (1500 3775) SIG_NAME M_D_CPU1_SA_DQS_DP<4>
J 0
(1510 3785);
DISPLAY 0.659574 (1510 3785);
PAINT MONO (1510 3785);
DISPLAY INVISIBLE (1510 3785);
FORCEPROP 1 LASTPIN (1500 3775) BN 4
J 0
(1488 3783);
DISPLAY 0.680851 (1488 3783);
PAINT GREEN (1488 3783);
FORCEPROP 2 LAST CDS_LIB standard
J 0
(1550 3775);
PAINT MONO (1550 3775);
DISPLAY INVISIBLE (1550 3775);
FORCEPROP 1 LAST BODY_TYPE PLUMBING
J 0
(1550 3825);
DISPLAY 0.872340 (1550 3825);
PAINT GREEN (1550 3825);
DISPLAY INVISIBLE (1550 3825);
FORCEPROP 1 LAST HDL_TAP TRUE
J 0
(1875 3650);
DISPLAY 0.872340 (1875 3650);
DISPLAY INVISIBLE (1875 3650);
FORCEPROP 1 LAST PATH I142
J 0
(1548 3775);
DISPLAY 0.872340 (1548 3775);
PAINT GREEN (1548 3775);
DISPLAY INVISIBLE (1548 3775);
FORCEADD TAP..1
(1550 3875);
FORCEPROP 3 LASTPIN (1500 3875) SIG_NAME M_D_CPU1_SA_DQS_DP<5>
J 0
(1510 3885);
DISPLAY 0.659574 (1510 3885);
PAINT MONO (1510 3885);
DISPLAY INVISIBLE (1510 3885);
FORCEPROP 1 LASTPIN (1500 3875) BN 5
J 0
(1488 3883);
DISPLAY 0.680851 (1488 3883);
PAINT GREEN (1488 3883);
FORCEPROP 2 LAST CDS_LIB standard
J 0
(1550 3875);
DISPLAY INVISIBLE (1550 3875);
FORCEPROP 1 LAST BODY_TYPE PLUMBING
J 0
(1550 3925);
DISPLAY 0.872340 (1550 3925);
PAINT GREEN (1550 3925);
DISPLAY INVISIBLE (1550 3925);
FORCEPROP 1 LAST HDL_TAP TRUE
J 0
(1875 3750);
DISPLAY 0.872340 (1875 3750);
DISPLAY INVISIBLE (1875 3750);
FORCEPROP 1 LAST PATH I143
J 0
(1548 3875);
DISPLAY 0.872340 (1548 3875);
PAINT GREEN (1548 3875);
DISPLAY INVISIBLE (1548 3875);
FORCEADD TAP..1
(1550 3975);
FORCEPROP 3 LASTPIN (1500 3975) SIG_NAME M_D_CPU1_SA_DQS_DP<6>
J 0
(1510 3985);
DISPLAY 0.659574 (1510 3985);
PAINT MONO (1510 3985);
DISPLAY INVISIBLE (1510 3985);
FORCEPROP 1 LASTPIN (1500 3975) BN 6
J 0
(1488 3983);
DISPLAY 0.680851 (1488 3983);
PAINT GREEN (1488 3983);
FORCEPROP 2 LAST CDS_LIB standard
J 0
(1550 3975);
DISPLAY INVISIBLE (1550 3975);
FORCEPROP 1 LAST BODY_TYPE PLUMBING
J 0
(1550 4025);
DISPLAY 0.872340 (1550 4025);
PAINT GREEN (1550 4025);
DISPLAY INVISIBLE (1550 4025);
FORCEPROP 1 LAST HDL_TAP TRUE
J 0
(1875 3850);
DISPLAY 0.872340 (1875 3850);
DISPLAY INVISIBLE (1875 3850);
FORCEPROP 1 LAST PATH I144
J 0
(1548 3975);
DISPLAY 0.872340 (1548 3975);
PAINT GREEN (1548 3975);
DISPLAY INVISIBLE (1548 3975);
FORCEADD TAP..1
(1550 4075);
FORCEPROP 3 LASTPIN (1500 4075) SIG_NAME M_D_CPU1_SA_DQS_DP<7>
J 0
(1510 4085);
DISPLAY 0.659574 (1510 4085);
PAINT MONO (1510 4085);
DISPLAY INVISIBLE (1510 4085);
FORCEPROP 1 LASTPIN (1500 4075) BN 7
J 0
(1488 4083);
DISPLAY 0.680851 (1488 4083);
PAINT GREEN (1488 4083);
FORCEPROP 2 LAST CDS_LIB standard
J 0
(1550 4075);
DISPLAY INVISIBLE (1550 4075);
FORCEPROP 1 LAST BODY_TYPE PLUMBING
J 0
(1550 4125);
DISPLAY 0.872340 (1550 4125);
PAINT GREEN (1550 4125);
DISPLAY INVISIBLE (1550 4125);
FORCEPROP 1 LAST HDL_TAP TRUE
J 0
(1875 3950);
DISPLAY 0.872340 (1875 3950);
DISPLAY INVISIBLE (1875 3950);
FORCEPROP 1 LAST PATH I145
J 0
(1548 4075);
DISPLAY 0.872340 (1548 4075);
PAINT GREEN (1548 4075);
DISPLAY INVISIBLE (1548 4075);
FORCEADD Q_CAP..1
(2150 400);
FORCEPROP 1 LAST PART_NUMBER CH6103KEA00
J 0
(2200 250);
DISPLAY 0.978723 (2200 250);
DISPLAY INVISIBLE (2200 250);
FORCEPROP 1 LAST TOLERANCE 10%
J 0
(2200 350);
DISPLAY 0.978723 (2200 350);
FORCEPROP 1 LAST VOLTAGE 16V
J 0
(2200 400);
DISPLAY 0.978723 (2200 400);
FORCEPROP 1 LAST PACK_TYPE C0805
J 0
(2200 200);
DISPLAY 0.978723 (2200 200);
FORCEPROP 1 LAST VALUE 10UF
J 0
(2200 450);
DISPLAY 0.978723 (2200 450);
FORCEPROP 1 LAST MATERIAL X6S
J 0
(2200 300);
DISPLAY 0.978723 (2200 300);
FORCEPROP 1 LAST $LOCATION C98
J 0
(2200 500);
DISPLAY 0.978723 (2200 500);
FORCEPROP 1 LASTPIN (2150 500) $PN 1
J 0
(2160 480);
DISPLAY 0.787234 (2160 480);
FORCEPROP 1 LASTPIN (2150 300) $PN 2
J 0
(2160 280);
DISPLAY 0.787234 (2160 280);
FORCEPROP 2 LAST CDS_LIB pure_quanta
J 0
(2150 400);
PAINT MONO (2150 400);
DISPLAY INVISIBLE (2150 400);
FORCEPROP 1 LAST PATH I146
J 0
(2200 550);
DISPLAY 0.978723 (2200 550);
PAINT WHITE (2200 550);
DISPLAY INVISIBLE (2200 550);
FORCEPROP 1 LAST $LOCATION C98
J 0
(2200 600);
DISPLAY 1.021277 (2200 600);
DISPLAY INVISIBLE (2200 600);
FORCEPROP 2 LAST CDS_LOCATION C98
J 0
(2200 600);
DISPLAY 1.021277 (2200 600);
DISPLAY INVISIBLE (2200 600);
FORCEPROP 2 LAST $SEC 1
J 0
(2200 600);
DISPLAY 0.680851 (2200 600);
PAINT MONO (2200 600);
DISPLAY INVISIBLE (2200 600);
FORCEPROP 2 LAST CDS_SEC 1
J 0
(2200 600);
DISPLAY 1.021277 (2200 600);
DISPLAY INVISIBLE (2200 600);
FORCEADD UNIVERSAL_GND..1
(3225 575);
FORCEPROP 3 LASTPIN (3225 625) SIG_NAME GND\g
J 0
(3235 635);
DISPLAY 0.659574 (3235 635);
PAINT MONO (3235 635);
DISPLAY INVISIBLE (3235 635);
FORCEPROP 1 LAST PATH I147
J 0
(3300 575);
DISPLAY 0.872340 (3300 575);
PAINT AQUA (3300 575);
DISPLAY INVISIBLE (3300 575);
FORCEPROP 1 LAST HDL_POWER GND
J 1
(3250 500);
DISPLAY 0.872340 (3250 500);
PAINT GREEN (3250 500);
DISPLAY INVISIBLE (3250 500);
FORCEPROP 2 LAST CDS_LIB logical_power
J 0
(3225 575);
PAINT MONO (3225 575);
DISPLAY INVISIBLE (3225 575);
FORCEADD TAP..1
(1725 2375);
FORCEPROP 3 LASTPIN (1675 2375) SIG_NAME M_D_CPU1_SB_DQS_DN<1>
J 0
(1685 2385);
DISPLAY 0.659574 (1685 2385);
PAINT MONO (1685 2385);
DISPLAY INVISIBLE (1685 2385);
FORCEPROP 1 LASTPIN (1675 2375) BN 1
J 0
(1663 2383);
DISPLAY 0.680851 (1663 2383);
PAINT GREEN (1663 2383);
FORCEPROP 2 LAST CDS_LIB standard
J 0
(1725 2375);
DISPLAY INVISIBLE (1725 2375);
FORCEPROP 1 LAST BODY_TYPE PLUMBING
J 0
(1725 2425);
DISPLAY 0.872340 (1725 2425);
PAINT GREEN (1725 2425);
DISPLAY INVISIBLE (1725 2425);
FORCEPROP 1 LAST HDL_TAP TRUE
J 0
(2050 2250);
DISPLAY 0.872340 (2050 2250);
DISPLAY INVISIBLE (2050 2250);
FORCEPROP 1 LAST PATH I149
J 0
(1723 2375);
DISPLAY 0.872340 (1723 2375);
PAINT GREEN (1723 2375);
DISPLAY INVISIBLE (1723 2375);
FORCEADD OFFPAGE..3
R 2
(-3775 2450);
FORCEPROP 2 LAST $XR1 104 
J 0
(-4144 2450);
DISPLAY 0.638298 (-4144 2450);
PAINT MONO (-4144 2450);
FORCEPROP 2 LAST $XR0 54 
J 0
(-4024 2450);
DISPLAY 0.638298 (-4024 2450);
PAINT MONO (-4024 2450);
FORCEPROP 2 LAST CDS_LIB standard
J 0
(-3775 2450);
PAINT MONO (-3775 2450);
DISPLAY INVISIBLE (-3775 2450);
FORCEPROP 1 LAST OFFPAGE TRUE
J 2
(-4100 2325);
DISPLAY 0.872340 (-4100 2325);
DISPLAY INVISIBLE (-4100 2325);
FORCEPROP 1 LAST COMMENT_BODY TRUE
J 2
(-3725 2350);
DISPLAY 0.872340 (-3725 2350);
PAINT GREEN (-3725 2350);
DISPLAY INVISIBLE (-3725 2350);
FORCEPROP 2 LAST PATH I15
J 0
(-3725 2525);
DISPLAY 1.021277 (-3725 2525);
DISPLAY INVISIBLE (-3725 2525);
FORCEADD TAP..1
(1725 2275);
FORCEPROP 3 LASTPIN (1675 2275) SIG_NAME M_D_CPU1_SB_DQS_DN<0>
J 0
(1685 2285);
DISPLAY 0.659574 (1685 2285);
PAINT MONO (1685 2285);
DISPLAY INVISIBLE (1685 2285);
FORCEPROP 1 LASTPIN (1675 2275) BN 0
J 0
(1663 2283);
DISPLAY 0.680851 (1663 2283);
PAINT GREEN (1663 2283);
FORCEPROP 2 LAST CDS_LIB standard
J 0
(1725 2275);
PAINT MONO (1725 2275);
DISPLAY INVISIBLE (1725 2275);
FORCEPROP 1 LAST BODY_TYPE PLUMBING
J 0
(1725 2325);
DISPLAY 0.872340 (1725 2325);
PAINT GREEN (1725 2325);
DISPLAY INVISIBLE (1725 2325);
FORCEPROP 1 LAST HDL_TAP TRUE
J 0
(2050 2150);
DISPLAY 0.872340 (2050 2150);
DISPLAY INVISIBLE (2050 2150);
FORCEPROP 1 LAST PATH I150
J 0
(1723 2275);
DISPLAY 0.872340 (1723 2275);
PAINT GREEN (1723 2275);
DISPLAY INVISIBLE (1723 2275);
FORCEADD TAP..1
(1725 2475);
FORCEPROP 3 LASTPIN (1675 2475) SIG_NAME M_D_CPU1_SB_DQS_DN<2>
J 0
(1685 2485);
DISPLAY 0.659574 (1685 2485);
PAINT MONO (1685 2485);
DISPLAY INVISIBLE (1685 2485);
FORCEPROP 1 LASTPIN (1675 2475) BN 2
J 0
(1663 2483);
DISPLAY 0.680851 (1663 2483);
PAINT GREEN (1663 2483);
FORCEPROP 2 LAST CDS_LIB standard
J 0
(1725 2475);
DISPLAY INVISIBLE (1725 2475);
FORCEPROP 1 LAST BODY_TYPE PLUMBING
J 0
(1725 2525);
DISPLAY 0.872340 (1725 2525);
PAINT GREEN (1725 2525);
DISPLAY INVISIBLE (1725 2525);
FORCEPROP 1 LAST HDL_TAP TRUE
J 0
(2050 2350);
DISPLAY 0.872340 (2050 2350);
DISPLAY INVISIBLE (2050 2350);
FORCEPROP 1 LAST PATH I151
J 0
(1723 2475);
DISPLAY 0.872340 (1723 2475);
PAINT GREEN (1723 2475);
DISPLAY INVISIBLE (1723 2475);
FORCEADD TAP..1
(1725 2575);
FORCEPROP 3 LASTPIN (1675 2575) SIG_NAME M_D_CPU1_SB_DQS_DN<3>
J 0
(1685 2585);
DISPLAY 0.659574 (1685 2585);
PAINT MONO (1685 2585);
DISPLAY INVISIBLE (1685 2585);
FORCEPROP 1 LASTPIN (1675 2575) BN 3
J 0
(1663 2583);
DISPLAY 0.680851 (1663 2583);
PAINT GREEN (1663 2583);
FORCEPROP 2 LAST CDS_LIB standard
J 0
(1725 2575);
PAINT MONO (1725 2575);
DISPLAY INVISIBLE (1725 2575);
FORCEPROP 1 LAST BODY_TYPE PLUMBING
J 0
(1725 2625);
DISPLAY 0.872340 (1725 2625);
PAINT GREEN (1725 2625);
DISPLAY INVISIBLE (1725 2625);
FORCEPROP 1 LAST HDL_TAP TRUE
J 0
(2050 2450);
DISPLAY 0.872340 (2050 2450);
DISPLAY INVISIBLE (2050 2450);
FORCEPROP 1 LAST PATH I152
J 0
(1723 2575);
DISPLAY 0.872340 (1723 2575);
PAINT GREEN (1723 2575);
DISPLAY INVISIBLE (1723 2575);
FORCEADD TAP..1
(1725 2675);
FORCEPROP 3 LASTPIN (1675 2675) SIG_NAME M_D_CPU1_SB_DQS_DN<4>
J 0
(1685 2685);
DISPLAY 0.659574 (1685 2685);
PAINT MONO (1685 2685);
DISPLAY INVISIBLE (1685 2685);
FORCEPROP 1 LASTPIN (1675 2675) BN 4
J 0
(1663 2683);
DISPLAY 0.680851 (1663 2683);
PAINT GREEN (1663 2683);
FORCEPROP 2 LAST CDS_LIB standard
J 0
(1725 2675);
PAINT MONO (1725 2675);
DISPLAY INVISIBLE (1725 2675);
FORCEPROP 1 LAST BODY_TYPE PLUMBING
J 0
(1725 2725);
DISPLAY 0.872340 (1725 2725);
PAINT GREEN (1725 2725);
DISPLAY INVISIBLE (1725 2725);
FORCEPROP 1 LAST HDL_TAP TRUE
J 0
(2050 2550);
DISPLAY 0.872340 (2050 2550);
DISPLAY INVISIBLE (2050 2550);
FORCEPROP 1 LAST PATH I153
J 0
(1723 2675);
DISPLAY 0.872340 (1723 2675);
PAINT GREEN (1723 2675);
DISPLAY INVISIBLE (1723 2675);
FORCEADD TAP..1
(1725 2775);
FORCEPROP 3 LASTPIN (1675 2775) SIG_NAME M_D_CPU1_SB_DQS_DN<5>
J 0
(1685 2785);
DISPLAY 0.659574 (1685 2785);
PAINT MONO (1685 2785);
DISPLAY INVISIBLE (1685 2785);
FORCEPROP 1 LASTPIN (1675 2775) BN 5
J 0
(1663 2783);
DISPLAY 0.680851 (1663 2783);
PAINT GREEN (1663 2783);
FORCEPROP 2 LAST CDS_LIB standard
J 0
(1725 2775);
DISPLAY INVISIBLE (1725 2775);
FORCEPROP 1 LAST BODY_TYPE PLUMBING
J 0
(1725 2825);
DISPLAY 0.872340 (1725 2825);
PAINT GREEN (1725 2825);
DISPLAY INVISIBLE (1725 2825);
FORCEPROP 1 LAST HDL_TAP TRUE
J 0
(2050 2650);
DISPLAY 0.872340 (2050 2650);
DISPLAY INVISIBLE (2050 2650);
FORCEPROP 1 LAST PATH I154
J 0
(1723 2775);
DISPLAY 0.872340 (1723 2775);
PAINT GREEN (1723 2775);
DISPLAY INVISIBLE (1723 2775);
FORCEADD TAP..1
(1725 2875);
FORCEPROP 3 LASTPIN (1675 2875) SIG_NAME M_D_CPU1_SB_DQS_DN<6>
J 0
(1685 2885);
DISPLAY 0.659574 (1685 2885);
PAINT MONO (1685 2885);
DISPLAY INVISIBLE (1685 2885);
FORCEPROP 1 LASTPIN (1675 2875) BN 6
J 0
(1663 2883);
DISPLAY 0.680851 (1663 2883);
PAINT GREEN (1663 2883);
FORCEPROP 2 LAST CDS_LIB standard
J 0
(1725 2875);
DISPLAY INVISIBLE (1725 2875);
FORCEPROP 1 LAST BODY_TYPE PLUMBING
J 0
(1725 2925);
DISPLAY 0.872340 (1725 2925);
PAINT GREEN (1725 2925);
DISPLAY INVISIBLE (1725 2925);
FORCEPROP 1 LAST HDL_TAP TRUE
J 0
(2050 2750);
DISPLAY 0.872340 (2050 2750);
DISPLAY INVISIBLE (2050 2750);
FORCEPROP 1 LAST PATH I155
J 0
(1723 2875);
DISPLAY 0.872340 (1723 2875);
PAINT GREEN (1723 2875);
DISPLAY INVISIBLE (1723 2875);
FORCEADD TAP..1
(1725 2975);
FORCEPROP 3 LASTPIN (1675 2975) SIG_NAME M_D_CPU1_SB_DQS_DN<7>
J 0
(1685 2985);
DISPLAY 0.659574 (1685 2985);
PAINT MONO (1685 2985);
DISPLAY INVISIBLE (1685 2985);
FORCEPROP 1 LASTPIN (1675 2975) BN 7
J 0
(1663 2983);
DISPLAY 0.680851 (1663 2983);
PAINT GREEN (1663 2983);
FORCEPROP 2 LAST CDS_LIB standard
J 0
(1725 2975);
DISPLAY INVISIBLE (1725 2975);
FORCEPROP 1 LAST BODY_TYPE PLUMBING
J 0
(1725 3025);
DISPLAY 0.872340 (1725 3025);
PAINT GREEN (1725 3025);
DISPLAY INVISIBLE (1725 3025);
FORCEPROP 1 LAST HDL_TAP TRUE
J 0
(2050 2850);
DISPLAY 0.872340 (2050 2850);
DISPLAY INVISIBLE (2050 2850);
FORCEPROP 1 LAST PATH I156
J 0
(1723 2975);
DISPLAY 0.872340 (1723 2975);
PAINT GREEN (1723 2975);
DISPLAY INVISIBLE (1723 2975);
FORCEADD TAP..1
(1725 3075);
FORCEPROP 3 LASTPIN (1675 3075) SIG_NAME M_D_CPU1_SB_DQS_DN<8>
J 0
(1685 3085);
DISPLAY 0.659574 (1685 3085);
PAINT MONO (1685 3085);
DISPLAY INVISIBLE (1685 3085);
FORCEPROP 1 LASTPIN (1675 3075) BN 8
J 0
(1663 3083);
DISPLAY 0.680851 (1663 3083);
PAINT GREEN (1663 3083);
FORCEPROP 2 LAST CDS_LIB standard
J 0
(1725 3075);
DISPLAY INVISIBLE (1725 3075);
FORCEPROP 1 LAST BODY_TYPE PLUMBING
J 0
(1725 3125);
DISPLAY 0.872340 (1725 3125);
PAINT GREEN (1725 3125);
DISPLAY INVISIBLE (1725 3125);
FORCEPROP 1 LAST HDL_TAP TRUE
J 0
(2050 2950);
DISPLAY 0.872340 (2050 2950);
DISPLAY INVISIBLE (2050 2950);
FORCEPROP 1 LAST PATH I157
J 0
(1723 3075);
DISPLAY 0.872340 (1723 3075);
PAINT GREEN (1723 3075);
DISPLAY INVISIBLE (1723 3075);
FORCEADD TAP..1
(1725 3175);
FORCEPROP 3 LASTPIN (1675 3175) SIG_NAME M_D_CPU1_SB_DQS_DN<9>
J 0
(1685 3185);
DISPLAY 0.659574 (1685 3185);
PAINT MONO (1685 3185);
DISPLAY INVISIBLE (1685 3185);
FORCEPROP 1 LASTPIN (1675 3175) BN 9
J 0
(1663 3183);
DISPLAY 0.680851 (1663 3183);
PAINT GREEN (1663 3183);
FORCEPROP 2 LAST CDS_LIB standard
J 0
(1725 3175);
DISPLAY INVISIBLE (1725 3175);
FORCEPROP 1 LAST BODY_TYPE PLUMBING
J 0
(1725 3225);
DISPLAY 0.872340 (1725 3225);
PAINT GREEN (1725 3225);
DISPLAY INVISIBLE (1725 3225);
FORCEPROP 1 LAST HDL_TAP TRUE
J 0
(2050 3050);
DISPLAY 0.872340 (2050 3050);
DISPLAY INVISIBLE (2050 3050);
FORCEPROP 1 LAST PATH I158
J 0
(1723 3175);
DISPLAY 0.872340 (1723 3175);
PAINT GREEN (1723 3175);
DISPLAY INVISIBLE (1723 3175);
FORCEADD TAP..1
(1725 3325);
FORCEPROP 3 LASTPIN (1675 3325) SIG_NAME M_D_CPU1_SA_DQS_DN<0>
J 0
(1685 3335);
DISPLAY 0.659574 (1685 3335);
PAINT MONO (1685 3335);
DISPLAY INVISIBLE (1685 3335);
FORCEPROP 1 LASTPIN (1675 3325) BN 0
J 0
(1663 3333);
DISPLAY 0.680851 (1663 3333);
PAINT GREEN (1663 3333);
FORCEPROP 2 LAST CDS_LIB standard
J 0
(1725 3325);
PAINT MONO (1725 3325);
DISPLAY INVISIBLE (1725 3325);
FORCEPROP 1 LAST BODY_TYPE PLUMBING
J 0
(1725 3375);
DISPLAY 0.872340 (1725 3375);
PAINT GREEN (1725 3375);
DISPLAY INVISIBLE (1725 3375);
FORCEPROP 1 LAST HDL_TAP TRUE
J 0
(2050 3200);
DISPLAY 0.872340 (2050 3200);
DISPLAY INVISIBLE (2050 3200);
FORCEPROP 1 LAST PATH I159
J 0
(1723 3325);
DISPLAY 0.872340 (1723 3325);
PAINT GREEN (1723 3325);
DISPLAY INVISIBLE (1723 3325);
FORCEADD OFFPAGE..3
R 2
(-3775 2900);
FORCEPROP 2 LAST $XR1 104 
J 0
(-4144 2900);
DISPLAY 0.638298 (-4144 2900);
PAINT MONO (-4144 2900);
FORCEPROP 2 LAST $XR0 54 
J 0
(-4024 2900);
DISPLAY 0.638298 (-4024 2900);
PAINT MONO (-4024 2900);
FORCEPROP 2 LAST CDS_LIB standard
J 0
(-3775 2900);
PAINT MONO (-3775 2900);
DISPLAY INVISIBLE (-3775 2900);
FORCEPROP 1 LAST OFFPAGE TRUE
J 2
(-4100 2775);
DISPLAY 0.872340 (-4100 2775);
DISPLAY INVISIBLE (-4100 2775);
FORCEPROP 1 LAST COMMENT_BODY TRUE
J 2
(-3725 2800);
DISPLAY 0.872340 (-3725 2800);
PAINT GREEN (-3725 2800);
DISPLAY INVISIBLE (-3725 2800);
FORCEPROP 2 LAST PATH I16
J 0
(-3725 2975);
DISPLAY 1.021277 (-3725 2975);
DISPLAY INVISIBLE (-3725 2975);
FORCEADD TAP..1
(1725 3525);
FORCEPROP 3 LASTPIN (1675 3525) SIG_NAME M_D_CPU1_SA_DQS_DN<2>
J 0
(1685 3535);
DISPLAY 0.659574 (1685 3535);
PAINT MONO (1685 3535);
DISPLAY INVISIBLE (1685 3535);
FORCEPROP 1 LASTPIN (1675 3525) BN 2
J 0
(1663 3533);
DISPLAY 0.680851 (1663 3533);
PAINT GREEN (1663 3533);
FORCEPROP 2 LAST CDS_LIB standard
J 0
(1725 3525);
DISPLAY INVISIBLE (1725 3525);
FORCEPROP 1 LAST BODY_TYPE PLUMBING
J 0
(1725 3575);
DISPLAY 0.872340 (1725 3575);
PAINT GREEN (1725 3575);
DISPLAY INVISIBLE (1725 3575);
FORCEPROP 1 LAST HDL_TAP TRUE
J 0
(2050 3400);
DISPLAY 0.872340 (2050 3400);
DISPLAY INVISIBLE (2050 3400);
FORCEPROP 1 LAST PATH I160
J 0
(1723 3525);
DISPLAY 0.872340 (1723 3525);
PAINT GREEN (1723 3525);
DISPLAY INVISIBLE (1723 3525);
FORCEADD TAP..1
(1725 3425);
FORCEPROP 3 LASTPIN (1675 3425) SIG_NAME M_D_CPU1_SA_DQS_DN<1>
J 0
(1685 3435);
DISPLAY 0.659574 (1685 3435);
PAINT MONO (1685 3435);
DISPLAY INVISIBLE (1685 3435);
FORCEPROP 1 LASTPIN (1675 3425) BN 1
J 0
(1663 3433);
DISPLAY 0.680851 (1663 3433);
PAINT GREEN (1663 3433);
FORCEPROP 2 LAST CDS_LIB standard
J 0
(1725 3425);
DISPLAY INVISIBLE (1725 3425);
FORCEPROP 1 LAST BODY_TYPE PLUMBING
J 0
(1725 3475);
DISPLAY 0.872340 (1725 3475);
PAINT GREEN (1725 3475);
DISPLAY INVISIBLE (1725 3475);
FORCEPROP 1 LAST HDL_TAP TRUE
J 0
(2050 3300);
DISPLAY 0.872340 (2050 3300);
DISPLAY INVISIBLE (2050 3300);
FORCEPROP 1 LAST PATH I161
J 0
(1723 3425);
DISPLAY 0.872340 (1723 3425);
PAINT GREEN (1723 3425);
DISPLAY INVISIBLE (1723 3425);
FORCEADD TAP..1
(1725 3625);
FORCEPROP 3 LASTPIN (1675 3625) SIG_NAME M_D_CPU1_SA_DQS_DN<3>
J 0
(1685 3635);
DISPLAY 0.659574 (1685 3635);
PAINT MONO (1685 3635);
DISPLAY INVISIBLE (1685 3635);
FORCEPROP 1 LASTPIN (1675 3625) BN 3
J 0
(1663 3633);
DISPLAY 0.680851 (1663 3633);
PAINT GREEN (1663 3633);
FORCEPROP 2 LAST CDS_LIB standard
J 0
(1725 3625);
PAINT MONO (1725 3625);
DISPLAY INVISIBLE (1725 3625);
FORCEPROP 1 LAST BODY_TYPE PLUMBING
J 0
(1725 3675);
DISPLAY 0.872340 (1725 3675);
PAINT GREEN (1725 3675);
DISPLAY INVISIBLE (1725 3675);
FORCEPROP 1 LAST HDL_TAP TRUE
J 0
(2050 3500);
DISPLAY 0.872340 (2050 3500);
DISPLAY INVISIBLE (2050 3500);
FORCEPROP 1 LAST PATH I162
J 0
(1723 3625);
DISPLAY 0.872340 (1723 3625);
PAINT GREEN (1723 3625);
DISPLAY INVISIBLE (1723 3625);
FORCEADD TAP..1
(1725 3725);
FORCEPROP 3 LASTPIN (1675 3725) SIG_NAME M_D_CPU1_SA_DQS_DN<4>
J 0
(1685 3735);
DISPLAY 0.659574 (1685 3735);
PAINT MONO (1685 3735);
DISPLAY INVISIBLE (1685 3735);
FORCEPROP 1 LASTPIN (1675 3725) BN 4
J 0
(1663 3733);
DISPLAY 0.680851 (1663 3733);
PAINT GREEN (1663 3733);
FORCEPROP 2 LAST CDS_LIB standard
J 0
(1725 3725);
PAINT MONO (1725 3725);
DISPLAY INVISIBLE (1725 3725);
FORCEPROP 1 LAST BODY_TYPE PLUMBING
J 0
(1725 3775);
DISPLAY 0.872340 (1725 3775);
PAINT GREEN (1725 3775);
DISPLAY INVISIBLE (1725 3775);
FORCEPROP 1 LAST HDL_TAP TRUE
J 0
(2050 3600);
DISPLAY 0.872340 (2050 3600);
DISPLAY INVISIBLE (2050 3600);
FORCEPROP 1 LAST PATH I163
J 0
(1723 3725);
DISPLAY 0.872340 (1723 3725);
PAINT GREEN (1723 3725);
DISPLAY INVISIBLE (1723 3725);
FORCEADD TAP..1
(1725 3825);
FORCEPROP 3 LASTPIN (1675 3825) SIG_NAME M_D_CPU1_SA_DQS_DN<5>
J 0
(1685 3835);
DISPLAY 0.659574 (1685 3835);
PAINT MONO (1685 3835);
DISPLAY INVISIBLE (1685 3835);
FORCEPROP 1 LASTPIN (1675 3825) BN 5
J 0
(1663 3833);
DISPLAY 0.680851 (1663 3833);
PAINT GREEN (1663 3833);
FORCEPROP 2 LAST CDS_LIB standard
J 0
(1725 3825);
DISPLAY INVISIBLE (1725 3825);
FORCEPROP 1 LAST BODY_TYPE PLUMBING
J 0
(1725 3875);
DISPLAY 0.872340 (1725 3875);
PAINT GREEN (1725 3875);
DISPLAY INVISIBLE (1725 3875);
FORCEPROP 1 LAST HDL_TAP TRUE
J 0
(2050 3700);
DISPLAY 0.872340 (2050 3700);
DISPLAY INVISIBLE (2050 3700);
FORCEPROP 1 LAST PATH I164
J 0
(1723 3825);
DISPLAY 0.872340 (1723 3825);
PAINT GREEN (1723 3825);
DISPLAY INVISIBLE (1723 3825);
FORCEADD TAP..1
(1725 4025);
FORCEPROP 3 LASTPIN (1675 4025) SIG_NAME M_D_CPU1_SA_DQS_DN<7>
J 0
(1685 4035);
DISPLAY 0.659574 (1685 4035);
PAINT MONO (1685 4035);
DISPLAY INVISIBLE (1685 4035);
FORCEPROP 1 LASTPIN (1675 4025) BN 7
J 0
(1663 4033);
DISPLAY 0.680851 (1663 4033);
PAINT GREEN (1663 4033);
FORCEPROP 2 LAST CDS_LIB standard
J 0
(1725 4025);
DISPLAY INVISIBLE (1725 4025);
FORCEPROP 1 LAST BODY_TYPE PLUMBING
J 0
(1725 4075);
DISPLAY 0.872340 (1725 4075);
PAINT GREEN (1725 4075);
DISPLAY INVISIBLE (1725 4075);
FORCEPROP 1 LAST HDL_TAP TRUE
J 0
(2050 3900);
DISPLAY 0.872340 (2050 3900);
DISPLAY INVISIBLE (2050 3900);
FORCEPROP 1 LAST PATH I165
J 0
(1723 4025);
DISPLAY 0.872340 (1723 4025);
PAINT GREEN (1723 4025);
DISPLAY INVISIBLE (1723 4025);
FORCEADD TAP..1
(1725 3925);
FORCEPROP 3 LASTPIN (1675 3925) SIG_NAME M_D_CPU1_SA_DQS_DN<6>
J 0
(1685 3935);
DISPLAY 0.659574 (1685 3935);
PAINT MONO (1685 3935);
DISPLAY INVISIBLE (1685 3935);
FORCEPROP 1 LASTPIN (1675 3925) BN 6
J 0
(1663 3933);
DISPLAY 0.680851 (1663 3933);
PAINT GREEN (1663 3933);
FORCEPROP 2 LAST CDS_LIB standard
J 0
(1725 3925);
DISPLAY INVISIBLE (1725 3925);
FORCEPROP 1 LAST BODY_TYPE PLUMBING
J 0
(1725 3975);
DISPLAY 0.872340 (1725 3975);
PAINT GREEN (1725 3975);
DISPLAY INVISIBLE (1725 3975);
FORCEPROP 1 LAST HDL_TAP TRUE
J 0
(2050 3800);
DISPLAY 0.872340 (2050 3800);
DISPLAY INVISIBLE (2050 3800);
FORCEPROP 1 LAST PATH I166
J 0
(1723 3925);
DISPLAY 0.872340 (1723 3925);
PAINT GREEN (1723 3925);
DISPLAY INVISIBLE (1723 3925);
FORCEADD TAP..1
(1725 4125);
FORCEPROP 3 LASTPIN (1675 4125) SIG_NAME M_D_CPU1_SA_DQS_DN<8>
J 0
(1685 4135);
DISPLAY 0.659574 (1685 4135);
PAINT MONO (1685 4135);
DISPLAY INVISIBLE (1685 4135);
FORCEPROP 1 LASTPIN (1675 4125) BN 8
J 0
(1663 4133);
DISPLAY 0.680851 (1663 4133);
PAINT GREEN (1663 4133);
FORCEPROP 2 LAST CDS_LIB standard
J 0
(1725 4125);
DISPLAY INVISIBLE (1725 4125);
FORCEPROP 1 LAST BODY_TYPE PLUMBING
J 0
(1725 4175);
DISPLAY 0.872340 (1725 4175);
PAINT GREEN (1725 4175);
DISPLAY INVISIBLE (1725 4175);
FORCEPROP 1 LAST HDL_TAP TRUE
J 0
(2050 4000);
DISPLAY 0.872340 (2050 4000);
DISPLAY INVISIBLE (2050 4000);
FORCEPROP 1 LAST PATH I167
J 0
(1723 4125);
DISPLAY 0.872340 (1723 4125);
PAINT GREEN (1723 4125);
DISPLAY INVISIBLE (1723 4125);
FORCEADD OFFPAGE..2
(2675 3250);
FORCEPROP 2 LAST $XR1 104 
J 0
(2954 3250);
DISPLAY 0.638298 (2954 3250);
PAINT MONO (2954 3250);
FORCEPROP 2 LAST $XR0 54 
J 0
(2864 3250);
DISPLAY 0.638298 (2864 3250);
PAINT MONO (2864 3250);
FORCEPROP 2 LAST CDS_LIB standard
J 0
(2675 3250);
PAINT MONO (2675 3250);
DISPLAY INVISIBLE (2675 3250);
FORCEPROP 1 LAST OFFPAGE TRUE
J 0
(3000 3125);
DISPLAY 1.170213 (3000 3125);
PAINT GREEN (3000 3125);
DISPLAY INVISIBLE (3000 3125);
FORCEPROP 1 LAST COMMENT_BODY TRUE
J 0
(2630 3155);
DISPLAY 1.170213 (2630 3155);
PAINT GREEN (2630 3155);
DISPLAY INVISIBLE (2630 3155);
FORCEPROP 2 LAST PATH I168
J 0
(2850 3325);
DISPLAY 1.021277 (2850 3325);
DISPLAY INVISIBLE (2850 3325);
FORCEADD OFFPAGE..2
(2675 3200);
FORCEPROP 2 LAST $XR1 104 
J 0
(2954 3200);
DISPLAY 0.638298 (2954 3200);
PAINT MONO (2954 3200);
FORCEPROP 2 LAST $XR0 54 
J 0
(2864 3200);
DISPLAY 0.638298 (2864 3200);
PAINT MONO (2864 3200);
FORCEPROP 2 LAST CDS_LIB standard
J 0
(2675 3200);
PAINT MONO (2675 3200);
DISPLAY INVISIBLE (2675 3200);
FORCEPROP 1 LAST OFFPAGE TRUE
J 0
(3000 3075);
DISPLAY 1.170213 (3000 3075);
PAINT GREEN (3000 3075);
DISPLAY INVISIBLE (3000 3075);
FORCEPROP 1 LAST COMMENT_BODY TRUE
J 0
(2630 3105);
DISPLAY 1.170213 (2630 3105);
PAINT GREEN (2630 3105);
DISPLAY INVISIBLE (2630 3105);
FORCEPROP 2 LAST PATH I169
J 0
(2850 3275);
DISPLAY 1.021277 (2850 3275);
DISPLAY INVISIBLE (2850 3275);
FORCEADD OFFPAGE..1
(-3775 2975);
FORCEPROP 2 LAST $XR0 54 
J 0
(-3996 2975);
DISPLAY 0.638298 (-3996 2975);
PAINT MONO (-3996 2975);
FORCEPROP 2 LAST CDS_LIB standard
J 0
(-3775 2975);
PAINT MONO (-3775 2975);
DISPLAY INVISIBLE (-3775 2975);
FORCEPROP 1 LAST OFFPAGE TRUE
J 0
(-3450 2850);
DISPLAY 0.872340 (-3450 2850);
DISPLAY INVISIBLE (-3450 2850);
FORCEPROP 1 LAST COMMENT_BODY TRUE
J 0
(-3650 2875);
DISPLAY 0.872340 (-3650 2875);
PAINT GREEN (-3650 2875);
DISPLAY INVISIBLE (-3650 2875);
FORCEPROP 2 LAST PATH I17
J 0
(-3725 3050);
DISPLAY 1.021277 (-3725 3050);
DISPLAY INVISIBLE (-3725 3050);
FORCEADD OFFPAGE..3
(-375 4300);
FORCEPROP 2 LAST $XR1 104 
J 0
(-71 4300);
DISPLAY 0.638298 (-71 4300);
PAINT MONO (-71 4300);
FORCEPROP 2 LAST $XR0 54 
J 0
(-161 4300);
DISPLAY 0.638298 (-161 4300);
PAINT MONO (-161 4300);
FORCEPROP 2 LAST CDS_LIB standard
J 2
(-375 4300);
DISPLAY INVISIBLE (-375 4300);
FORCEPROP 1 LAST OFFPAGE TRUE
J 0
(-50 4175);
DISPLAY 0.872340 (-50 4175);
DISPLAY INVISIBLE (-50 4175);
FORCEPROP 1 LAST COMMENT_BODY TRUE
J 0
(-425 4200);
DISPLAY 0.872340 (-425 4200);
PAINT GREEN (-425 4200);
DISPLAY INVISIBLE (-425 4200);
FORCEPROP 2 LAST PATH I170
J 0
(-175 4375);
DISPLAY 1.021277 (-175 4375);
DISPLAY INVISIBLE (-175 4375);
FORCEADD TAP..1
(1550 4275);
FORCEPROP 3 LASTPIN (1500 4275) SIG_NAME M_D_CPU1_SA_DQS_DP<9>
J 0
(1510 4285);
DISPLAY 0.659574 (1510 4285);
PAINT MONO (1510 4285);
DISPLAY INVISIBLE (1510 4285);
FORCEPROP 1 LASTPIN (1500 4275) BN 9
J 0
(1488 4283);
DISPLAY 0.680851 (1488 4283);
PAINT GREEN (1488 4283);
FORCEPROP 2 LAST CDS_LIB standard
J 0
(1550 4275);
DISPLAY INVISIBLE (1550 4275);
FORCEPROP 1 LAST BODY_TYPE PLUMBING
J 0
(1550 4325);
DISPLAY 0.872340 (1550 4325);
PAINT GREEN (1550 4325);
DISPLAY INVISIBLE (1550 4325);
FORCEPROP 1 LAST HDL_TAP TRUE
J 0
(1875 4150);
DISPLAY 0.872340 (1875 4150);
DISPLAY INVISIBLE (1875 4150);
FORCEPROP 1 LAST PATH I171
J 0
(1548 4275);
DISPLAY 0.872340 (1548 4275);
PAINT GREEN (1548 4275);
DISPLAY INVISIBLE (1548 4275);
FORCEADD TAP..1
(1550 4175);
FORCEPROP 3 LASTPIN (1500 4175) SIG_NAME M_D_CPU1_SA_DQS_DP<8>
J 0
(1510 4185);
DISPLAY 0.659574 (1510 4185);
PAINT MONO (1510 4185);
DISPLAY INVISIBLE (1510 4185);
FORCEPROP 1 LASTPIN (1500 4175) BN 8
J 0
(1488 4183);
DISPLAY 0.680851 (1488 4183);
PAINT GREEN (1488 4183);
FORCEPROP 2 LAST CDS_LIB standard
J 0
(1550 4175);
DISPLAY INVISIBLE (1550 4175);
FORCEPROP 1 LAST BODY_TYPE PLUMBING
J 0
(1550 4225);
DISPLAY 0.872340 (1550 4225);
PAINT GREEN (1550 4225);
DISPLAY INVISIBLE (1550 4225);
FORCEPROP 1 LAST HDL_TAP TRUE
J 0
(1875 4050);
DISPLAY 0.872340 (1875 4050);
DISPLAY INVISIBLE (1875 4050);
FORCEPROP 1 LAST PATH I172
J 0
(1548 4175);
DISPLAY 0.872340 (1548 4175);
PAINT GREEN (1548 4175);
DISPLAY INVISIBLE (1548 4175);
FORCEADD TAP..1
(1725 4225);
FORCEPROP 3 LASTPIN (1675 4225) SIG_NAME M_D_CPU1_SA_DQS_DN<9>
J 0
(1685 4235);
DISPLAY 0.659574 (1685 4235);
PAINT MONO (1685 4235);
DISPLAY INVISIBLE (1685 4235);
FORCEPROP 1 LASTPIN (1675 4225) BN 9
J 0
(1663 4233);
DISPLAY 0.680851 (1663 4233);
PAINT GREEN (1663 4233);
FORCEPROP 2 LAST CDS_LIB standard
J 0
(1725 4225);
DISPLAY INVISIBLE (1725 4225);
FORCEPROP 1 LAST BODY_TYPE PLUMBING
J 0
(1725 4275);
DISPLAY 0.872340 (1725 4275);
PAINT GREEN (1725 4275);
DISPLAY INVISIBLE (1725 4275);
FORCEPROP 1 LAST HDL_TAP TRUE
J 0
(2050 4100);
DISPLAY 0.872340 (2050 4100);
DISPLAY INVISIBLE (2050 4100);
FORCEPROP 1 LAST PATH I173
J 0
(1723 4225);
DISPLAY 0.872340 (1723 4225);
PAINT GREEN (1723 4225);
DISPLAY INVISIBLE (1723 4225);
FORCEADD OFFPAGE..2
(2675 4250);
FORCEPROP 2 LAST $XR1 104 
J 0
(2954 4250);
DISPLAY 0.638298 (2954 4250);
PAINT MONO (2954 4250);
FORCEPROP 2 LAST $XR0 54 
J 0
(2864 4250);
DISPLAY 0.638298 (2864 4250);
PAINT MONO (2864 4250);
FORCEPROP 2 LAST CDS_LIB standard
J 0
(2675 4250);
PAINT MONO (2675 4250);
DISPLAY INVISIBLE (2675 4250);
FORCEPROP 1 LAST OFFPAGE TRUE
J 0
(3000 4125);
DISPLAY 1.170213 (3000 4125);
PAINT GREEN (3000 4125);
DISPLAY INVISIBLE (3000 4125);
FORCEPROP 1 LAST COMMENT_BODY TRUE
J 0
(2630 4155);
DISPLAY 1.170213 (2630 4155);
PAINT GREEN (2630 4155);
DISPLAY INVISIBLE (2630 4155);
FORCEPROP 2 LAST PATH I174
J 0
(2850 4325);
DISPLAY 1.021277 (2850 4325);
DISPLAY INVISIBLE (2850 4325);
FORCEADD OFFPAGE..2
(2675 4300);
FORCEPROP 2 LAST $XR1 104 
J 0
(2954 4300);
DISPLAY 0.638298 (2954 4300);
PAINT MONO (2954 4300);
FORCEPROP 2 LAST $XR0 54 
J 0
(2864 4300);
DISPLAY 0.638298 (2864 4300);
PAINT MONO (2864 4300);
FORCEPROP 2 LAST CDS_LIB standard
J 0
(2675 4300);
PAINT MONO (2675 4300);
DISPLAY INVISIBLE (2675 4300);
FORCEPROP 1 LAST OFFPAGE TRUE
J 0
(3000 4175);
DISPLAY 1.170213 (3000 4175);
PAINT GREEN (3000 4175);
DISPLAY INVISIBLE (3000 4175);
FORCEPROP 1 LAST COMMENT_BODY TRUE
J 0
(2630 4205);
DISPLAY 1.170213 (2630 4205);
PAINT GREEN (2630 4205);
DISPLAY INVISIBLE (2630 4205);
FORCEPROP 2 LAST PATH I175
J 0
(2850 4375);
DISPLAY 1.021277 (2850 4375);
DISPLAY INVISIBLE (2850 4375);
FORCEADD VCC_CORE..1
(3225 4825);
FORCEPROP 3 LASTPIN (3225 4775) SIG_NAME P12V_S3_AUX_CPU1_NVDIMM\g
J 0
(3235 4785);
DISPLAY 0.659574 (3235 4785);
PAINT MONO (3235 4785);
DISPLAY INVISIBLE (3235 4785);
FORCEPROP 1 LAST HDL_POWER P12V_S3_AUX_CPU1_NVDIMM
J 1
(3225 4875);
DISPLAY 1.148936 (3225 4875);
PAINT GREEN (3225 4875);
FORCEPROP 2 LAST CDS_LIB logical_power
J 0
(3225 4825);
PAINT MONO (3225 4825);
DISPLAY INVISIBLE (3225 4825);
FORCEPROP 1 LAST PATH I176
J 0
(3275 4850);
DISPLAY 0.872340 (3275 4850);
PAINT AQUA (3275 4850);
DISPLAY INVISIBLE (3275 4850);
FORCEADD UNIVERSAL_GND..1
(4925 575);
FORCEPROP 3 LASTPIN (4925 625) SIG_NAME GND\g
J 0
(4935 635);
DISPLAY 0.659574 (4935 635);
PAINT MONO (4935 635);
DISPLAY INVISIBLE (4935 635);
FORCEPROP 1 LAST PATH I177
J 0
(5000 575);
DISPLAY 0.872340 (5000 575);
PAINT AQUA (5000 575);
DISPLAY INVISIBLE (5000 575);
FORCEPROP 1 LAST HDL_POWER GND
J 1
(4950 500);
DISPLAY 0.872340 (4950 500);
PAINT GREEN (4950 500);
DISPLAY INVISIBLE (4950 500);
FORCEPROP 2 LAST CDS_LIB logical_power
J 0
(4925 575);
PAINT MONO (4925 575);
DISPLAY INVISIBLE (4925 575);
FORCEADD SCONN288_ADR50017P087CC..1
(-2025 2550);
FORCEPROP 1 LAST PART_NUMBER DFHST8FS460
J 0
(-2470 4560);
DISPLAY 0.723404 (-2470 4560);
PAINT GREEN (-2470 4560);
DISPLAY INVISIBLE (-2470 4560);
FORCEPROP 1 LAST MATERIAL IO
J 0
(-2470 4433);
DISPLAY 0.723404 (-2470 4433);
PAINT GREEN (-2470 4433);
FORCEPROP 2 LAST VALUE SCONN288_ADR50017-P087CC
J 0
(-2475 4675);
DISPLAY 1.021277 (-2475 4675);
FORCEPROP 2 LAST PART_TYPE SMLF
J 0
(-2475 4725);
DISPLAY 1.021277 (-2475 4725);
FORCEPROP 1 LAST $LOCATION J24
J 0
(-2475 4625);
DISPLAY 0.723404 (-2475 4625);
PAINT GREEN (-2475 4625);
FORCEPROP 0 LASTPIN (-2625 1925) $PN 62
J 2
(-2635 1935);
DISPLAY 0.680851 (-2635 1935);
PAINT MONO (-2635 1935);
FORCEPROP 0 LASTPIN (-2625 3975) $PN 66
J 2
(-2635 3985);
DISPLAY 0.680851 (-2635 3985);
PAINT MONO (-2635 3985);
FORCEPROP 0 LASTPIN (-2625 3575) $PN 76
J 2
(-2635 3585);
DISPLAY 0.680851 (-2635 3585);
PAINT MONO (-2635 3585);
FORCEPROP 0 LASTPIN (-2625 4025) $PN 211
J 2
(-2635 4035);
DISPLAY 0.680851 (-2635 4035);
PAINT MONO (-2635 4035);
FORCEPROP 0 LASTPIN (-2625 3625) $PN 221
J 2
(-2635 3635);
DISPLAY 0.680851 (-2635 3635);
PAINT MONO (-2635 3635);
FORCEPROP 0 LASTPIN (-2625 4075) $PN 68
J 2
(-2635 4085);
DISPLAY 0.680851 (-2635 4085);
PAINT MONO (-2635 4085);
FORCEPROP 0 LASTPIN (-2625 3675) $PN 78
J 2
(-2635 3685);
DISPLAY 0.680851 (-2635 3685);
PAINT MONO (-2635 3685);
FORCEPROP 0 LASTPIN (-2625 4125) $PN 213
J 2
(-2635 4135);
DISPLAY 0.680851 (-2635 4135);
PAINT MONO (-2635 4135);
FORCEPROP 0 LASTPIN (-2625 3725) $PN 223
J 2
(-2635 3735);
DISPLAY 0.680851 (-2635 3735);
PAINT MONO (-2635 3735);
FORCEPROP 0 LASTPIN (-2625 4175) $PN 70
J 2
(-2635 4185);
DISPLAY 0.680851 (-2635 4185);
PAINT MONO (-2635 4185);
FORCEPROP 0 LASTPIN (-2625 3775) $PN 80
J 2
(-2635 3785);
DISPLAY 0.680851 (-2635 3785);
PAINT MONO (-2635 3785);
FORCEPROP 0 LASTPIN (-2625 4225) $PN 215
J 2
(-2635 4235);
DISPLAY 0.680851 (-2635 4235);
PAINT MONO (-2635 4235);
FORCEPROP 0 LASTPIN (-2625 3825) $PN 225
J 2
(-2635 3835);
DISPLAY 0.680851 (-2635 3835);
PAINT MONO (-2635 3835);
FORCEPROP 0 LASTPIN (-2625 4275) $PN 72
J 2
(-2635 4285);
DISPLAY 0.680851 (-2635 4285);
PAINT MONO (-2635 4285);
FORCEPROP 0 LASTPIN (-2625 3875) $PN 82
J 2
(-2635 3885);
DISPLAY 0.680851 (-2635 3885);
PAINT MONO (-2635 3885);
FORCEPROP 0 LASTPIN (-2625 2525) $PN 51
J 2
(-2635 2535);
DISPLAY 0.680851 (-2635 2535);
PAINT MONO (-2635 2535);
FORCEPROP 0 LASTPIN (-2625 2075) $PN 96
J 2
(-2635 2085);
DISPLAY 0.680851 (-2635 2085);
PAINT MONO (-2635 2085);
FORCEPROP 0 LASTPIN (-2625 2575) $PN 53
J 2
(-2635 2585);
DISPLAY 0.680851 (-2635 2585);
PAINT MONO (-2635 2585);
FORCEPROP 0 LASTPIN (-2625 2125) $PN 98
J 2
(-2635 2135);
DISPLAY 0.680851 (-2635 2135);
PAINT MONO (-2635 2135);
FORCEPROP 0 LASTPIN (-2625 2625) $PN 196
J 2
(-2635 2635);
DISPLAY 0.680851 (-2635 2635);
PAINT MONO (-2635 2635);
FORCEPROP 0 LASTPIN (-2625 2175) $PN 241
J 2
(-2635 2185);
DISPLAY 0.680851 (-2635 2185);
PAINT MONO (-2635 2185);
FORCEPROP 0 LASTPIN (-2625 2675) $PN 198
J 2
(-2635 2685);
DISPLAY 0.680851 (-2635 2685);
PAINT MONO (-2635 2685);
FORCEPROP 0 LASTPIN (-2625 2225) $PN 243
J 2
(-2635 2235);
DISPLAY 0.680851 (-2635 2235);
PAINT MONO (-2635 2235);
FORCEPROP 0 LASTPIN (-2625 2725) $PN 58
J 2
(-2635 2735);
DISPLAY 0.680851 (-2635 2735);
PAINT MONO (-2635 2735);
FORCEPROP 0 LASTPIN (-2625 2275) $PN 89
J 2
(-2635 2285);
DISPLAY 0.680851 (-2635 2285);
PAINT MONO (-2635 2285);
FORCEPROP 0 LASTPIN (-2625 2775) $PN 60
J 2
(-2635 2785);
DISPLAY 0.680851 (-2635 2785);
PAINT MONO (-2635 2785);
FORCEPROP 0 LASTPIN (-2625 2325) $PN 91
J 2
(-2635 2335);
DISPLAY 0.680851 (-2635 2335);
PAINT MONO (-2635 2335);
FORCEPROP 0 LASTPIN (-2625 2825) $PN 203
J 2
(-2635 2835);
DISPLAY 0.680851 (-2635 2835);
PAINT MONO (-2635 2835);
FORCEPROP 0 LASTPIN (-2625 2375) $PN 234
J 2
(-2635 2385);
DISPLAY 0.680851 (-2635 2385);
PAINT MONO (-2635 2385);
FORCEPROP 0 LASTPIN (-2625 2875) $PN 205
J 2
(-2635 2885);
DISPLAY 0.680851 (-2635 2885);
PAINT MONO (-2635 2885);
FORCEPROP 0 LASTPIN (-2625 2425) $PN 236
J 2
(-2635 2435);
DISPLAY 0.680851 (-2635 2435);
PAINT MONO (-2635 2435);
FORCEPROP 0 LASTPIN (-2625 2975) $PN 218
J 2
(-2635 2985);
DISPLAY 0.680851 (-2635 2985);
PAINT MONO (-2635 2985);
FORCEPROP 0 LASTPIN (-2625 3025) $PN 217
J 2
(-2635 3035);
DISPLAY 0.680851 (-2635 3035);
PAINT MONO (-2635 3035);
FORCEPROP 0 LASTPIN (-2625 3275) $PN 64
J 2
(-2635 3285);
DISPLAY 0.680851 (-2635 3285);
PAINT MONO (-2635 3285);
FORCEPROP 0 LASTPIN (-2625 3125) $PN 84
J 2
(-2635 3135);
DISPLAY 0.680851 (-2635 3135);
PAINT MONO (-2635 3135);
FORCEPROP 0 LASTPIN (-2625 3325) $PN 209
J 2
(-2635 3335);
DISPLAY 0.680851 (-2635 3335);
PAINT MONO (-2635 3335);
FORCEPROP 0 LASTPIN (-2625 3175) $PN 229
J 2
(-2635 3185);
DISPLAY 0.680851 (-2635 3185);
PAINT MONO (-2635 3185);
FORCEPROP 0 LASTPIN (-1425 2725) $PN 7
J 0
(-1415 2735);
DISPLAY 0.680851 (-1415 2735);
PAINT MONO (-1415 2735);
FORCEPROP 0 LASTPIN (-1425 1075) $PN 100
J 0
(-1415 1085);
DISPLAY 0.680851 (-1415 1085);
PAINT MONO (-1415 1085);
FORCEPROP 0 LASTPIN (-1425 2775) $PN 9
J 0
(-1415 2785);
DISPLAY 0.680851 (-1415 2785);
PAINT MONO (-1415 2785);
FORCEPROP 0 LASTPIN (-1425 1125) $PN 102
J 0
(-1415 1135);
DISPLAY 0.680851 (-1415 1135);
PAINT MONO (-1415 1135);
FORCEPROP 0 LASTPIN (-1425 2825) $PN 152
J 0
(-1415 2835);
DISPLAY 0.680851 (-1415 2835);
PAINT MONO (-1415 2835);
FORCEPROP 0 LASTPIN (-1425 1175) $PN 245
J 0
(-1415 1185);
DISPLAY 0.680851 (-1415 1185);
PAINT MONO (-1415 1185);
FORCEPROP 0 LASTPIN (-1425 2875) $PN 154
J 0
(-1415 2885);
DISPLAY 0.680851 (-1415 2885);
PAINT MONO (-1415 2885);
FORCEPROP 0 LASTPIN (-1425 1225) $PN 247
J 0
(-1415 1235);
DISPLAY 0.680851 (-1415 1235);
PAINT MONO (-1415 1235);
FORCEPROP 0 LASTPIN (-1425 2925) $PN 14
J 0
(-1415 2935);
DISPLAY 0.680851 (-1415 2935);
PAINT MONO (-1415 2935);
FORCEPROP 0 LASTPIN (-1425 1275) $PN 107
J 0
(-1415 1285);
DISPLAY 0.680851 (-1415 1285);
PAINT MONO (-1415 1285);
FORCEPROP 0 LASTPIN (-1425 2975) $PN 16
J 0
(-1415 2985);
DISPLAY 0.680851 (-1415 2985);
PAINT MONO (-1415 2985);
FORCEPROP 0 LASTPIN (-1425 1325) $PN 109
J 0
(-1415 1335);
DISPLAY 0.680851 (-1415 1335);
PAINT MONO (-1415 1335);
FORCEPROP 0 LASTPIN (-1425 3025) $PN 159
J 0
(-1415 3035);
DISPLAY 0.680851 (-1415 3035);
PAINT MONO (-1415 3035);
FORCEPROP 0 LASTPIN (-1425 1375) $PN 252
J 0
(-1415 1385);
DISPLAY 0.680851 (-1415 1385);
PAINT MONO (-1415 1385);
FORCEPROP 0 LASTPIN (-1425 3075) $PN 161
J 0
(-1415 3085);
DISPLAY 0.680851 (-1415 3085);
PAINT MONO (-1415 3085);
FORCEPROP 0 LASTPIN (-1425 1425) $PN 254
J 0
(-1415 1435);
DISPLAY 0.680851 (-1415 1435);
PAINT MONO (-1415 1435);
FORCEPROP 0 LASTPIN (-1425 3125) $PN 18
J 0
(-1415 3135);
DISPLAY 0.680851 (-1415 3135);
PAINT MONO (-1415 3135);
FORCEPROP 0 LASTPIN (-1425 1475) $PN 111
J 0
(-1415 1485);
DISPLAY 0.680851 (-1415 1485);
PAINT MONO (-1415 1485);
FORCEPROP 0 LASTPIN (-1425 3175) $PN 20
J 0
(-1415 3185);
DISPLAY 0.680851 (-1415 3185);
PAINT MONO (-1415 3185);
FORCEPROP 0 LASTPIN (-1425 1525) $PN 113
J 0
(-1415 1535);
DISPLAY 0.680851 (-1415 1535);
PAINT MONO (-1415 1535);
FORCEPROP 0 LASTPIN (-1425 3225) $PN 163
J 0
(-1415 3235);
DISPLAY 0.680851 (-1415 3235);
PAINT MONO (-1415 3235);
FORCEPROP 0 LASTPIN (-1425 1575) $PN 256
J 0
(-1415 1585);
DISPLAY 0.680851 (-1415 1585);
PAINT MONO (-1415 1585);
FORCEPROP 0 LASTPIN (-1425 3275) $PN 165
J 0
(-1415 3285);
DISPLAY 0.680851 (-1415 3285);
PAINT MONO (-1415 3285);
FORCEPROP 0 LASTPIN (-1425 1625) $PN 258
J 0
(-1415 1635);
DISPLAY 0.680851 (-1415 1635);
PAINT MONO (-1415 1635);
FORCEPROP 0 LASTPIN (-1425 3325) $PN 25
J 0
(-1415 3335);
DISPLAY 0.680851 (-1415 3335);
PAINT MONO (-1415 3335);
FORCEPROP 0 LASTPIN (-1425 1675) $PN 118
J 0
(-1415 1685);
DISPLAY 0.680851 (-1415 1685);
PAINT MONO (-1415 1685);
FORCEPROP 0 LASTPIN (-1425 3375) $PN 27
J 0
(-1415 3385);
DISPLAY 0.680851 (-1415 3385);
PAINT MONO (-1415 3385);
FORCEPROP 0 LASTPIN (-1425 1725) $PN 120
J 0
(-1415 1735);
DISPLAY 0.680851 (-1415 1735);
PAINT MONO (-1415 1735);
FORCEPROP 0 LASTPIN (-1425 3425) $PN 170
J 0
(-1415 3435);
DISPLAY 0.680851 (-1415 3435);
PAINT MONO (-1415 3435);
FORCEPROP 0 LASTPIN (-1425 1775) $PN 263
J 0
(-1415 1785);
DISPLAY 0.680851 (-1415 1785);
PAINT MONO (-1415 1785);
FORCEPROP 0 LASTPIN (-1425 3475) $PN 172
J 0
(-1415 3485);
DISPLAY 0.680851 (-1415 3485);
PAINT MONO (-1415 3485);
FORCEPROP 0 LASTPIN (-1425 1825) $PN 265
J 0
(-1415 1835);
DISPLAY 0.680851 (-1415 1835);
PAINT MONO (-1415 1835);
FORCEPROP 0 LASTPIN (-1425 3525) $PN 29
J 0
(-1415 3535);
DISPLAY 0.680851 (-1415 3535);
PAINT MONO (-1415 3535);
FORCEPROP 0 LASTPIN (-1425 1875) $PN 122
J 0
(-1415 1885);
DISPLAY 0.680851 (-1415 1885);
PAINT MONO (-1415 1885);
FORCEPROP 0 LASTPIN (-1425 3575) $PN 31
J 0
(-1415 3585);
DISPLAY 0.680851 (-1415 3585);
PAINT MONO (-1415 3585);
FORCEPROP 0 LASTPIN (-1425 1925) $PN 124
J 0
(-1415 1935);
DISPLAY 0.680851 (-1415 1935);
PAINT MONO (-1415 1935);
FORCEPROP 0 LASTPIN (-1425 3625) $PN 174
J 0
(-1415 3635);
DISPLAY 0.680851 (-1415 3635);
PAINT MONO (-1415 3635);
FORCEPROP 0 LASTPIN (-1425 1975) $PN 267
J 0
(-1415 1985);
DISPLAY 0.680851 (-1415 1985);
PAINT MONO (-1415 1985);
FORCEPROP 0 LASTPIN (-1425 3675) $PN 176
J 0
(-1415 3685);
DISPLAY 0.680851 (-1415 3685);
PAINT MONO (-1415 3685);
FORCEPROP 0 LASTPIN (-1425 2025) $PN 269
J 0
(-1415 2035);
DISPLAY 0.680851 (-1415 2035);
PAINT MONO (-1415 2035);
FORCEPROP 0 LASTPIN (-1425 3725) $PN 36
J 0
(-1415 3735);
DISPLAY 0.680851 (-1415 3735);
PAINT MONO (-1415 3735);
FORCEPROP 0 LASTPIN (-1425 2075) $PN 129
J 0
(-1415 2085);
DISPLAY 0.680851 (-1415 2085);
PAINT MONO (-1415 2085);
FORCEPROP 0 LASTPIN (-1425 3775) $PN 38
J 0
(-1415 3785);
DISPLAY 0.680851 (-1415 3785);
PAINT MONO (-1415 3785);
FORCEPROP 0 LASTPIN (-1425 2125) $PN 131
J 0
(-1415 2135);
DISPLAY 0.680851 (-1415 2135);
PAINT MONO (-1415 2135);
FORCEPROP 0 LASTPIN (-1425 3825) $PN 181
J 0
(-1415 3835);
DISPLAY 0.680851 (-1415 3835);
PAINT MONO (-1415 3835);
FORCEPROP 0 LASTPIN (-1425 2175) $PN 274
J 0
(-1415 2185);
DISPLAY 0.680851 (-1415 2185);
PAINT MONO (-1415 2185);
FORCEPROP 0 LASTPIN (-1425 3875) $PN 183
J 0
(-1415 3885);
DISPLAY 0.680851 (-1415 3885);
PAINT MONO (-1415 3885);
FORCEPROP 0 LASTPIN (-1425 2225) $PN 276
J 0
(-1415 2235);
DISPLAY 0.680851 (-1415 2235);
PAINT MONO (-1415 2235);
FORCEPROP 0 LASTPIN (-1425 3925) $PN 40
J 0
(-1415 3935);
DISPLAY 0.680851 (-1415 3935);
PAINT MONO (-1415 3935);
FORCEPROP 0 LASTPIN (-1425 2275) $PN 133
J 0
(-1415 2285);
DISPLAY 0.680851 (-1415 2285);
PAINT MONO (-1415 2285);
FORCEPROP 0 LASTPIN (-1425 3975) $PN 42
J 0
(-1415 3985);
DISPLAY 0.680851 (-1415 3985);
PAINT MONO (-1415 3985);
FORCEPROP 0 LASTPIN (-1425 2325) $PN 135
J 0
(-1415 2335);
DISPLAY 0.680851 (-1415 2335);
PAINT MONO (-1415 2335);
FORCEPROP 0 LASTPIN (-1425 4025) $PN 185
J 0
(-1415 4035);
DISPLAY 0.680851 (-1415 4035);
PAINT MONO (-1415 4035);
FORCEPROP 0 LASTPIN (-1425 2375) $PN 278
J 0
(-1415 2385);
DISPLAY 0.680851 (-1415 2385);
PAINT MONO (-1415 2385);
FORCEPROP 0 LASTPIN (-1425 4075) $PN 187
J 0
(-1415 4085);
DISPLAY 0.680851 (-1415 4085);
PAINT MONO (-1415 4085);
FORCEPROP 0 LASTPIN (-1425 2425) $PN 280
J 0
(-1415 2435);
DISPLAY 0.680851 (-1415 2435);
PAINT MONO (-1415 2435);
FORCEPROP 0 LASTPIN (-1425 4125) $PN 47
J 0
(-1415 4135);
DISPLAY 0.680851 (-1415 4135);
PAINT MONO (-1415 4135);
FORCEPROP 0 LASTPIN (-1425 2475) $PN 140
J 0
(-1415 2485);
DISPLAY 0.680851 (-1415 2485);
PAINT MONO (-1415 2485);
FORCEPROP 0 LASTPIN (-1425 4175) $PN 49
J 0
(-1415 4185);
DISPLAY 0.680851 (-1415 4185);
PAINT MONO (-1415 4185);
FORCEPROP 0 LASTPIN (-1425 2525) $PN 142
J 0
(-1415 2535);
DISPLAY 0.680851 (-1415 2535);
PAINT MONO (-1415 2535);
FORCEPROP 0 LASTPIN (-1425 4225) $PN 192
J 0
(-1415 4235);
DISPLAY 0.680851 (-1415 4235);
PAINT MONO (-1415 4235);
FORCEPROP 0 LASTPIN (-1425 2575) $PN 285
J 0
(-1415 2585);
DISPLAY 0.680851 (-1415 2585);
PAINT MONO (-1415 2585);
FORCEPROP 0 LASTPIN (-1425 4275) $PN 194
J 0
(-1415 4285);
DISPLAY 0.680851 (-1415 4285);
PAINT MONO (-1415 4285);
FORCEPROP 0 LASTPIN (-1425 2625) $PN 287
J 0
(-1415 2635);
DISPLAY 0.680851 (-1415 2635);
PAINT MONO (-1415 2635);
FORCEPROP 0 LASTPIN (-2625 1775) $PN 148
J 2
(-2635 1785);
DISPLAY 0.680851 (-2635 1785);
PAINT MONO (-2635 1785);
FORCEPROP 0 LASTPIN (-2625 1675) $PN 4
J 2
(-2635 1685);
DISPLAY 0.680851 (-2635 1685);
PAINT MONO (-2635 1685);
FORCEPROP 0 LASTPIN (-2625 1725) $PN 5
J 2
(-2635 1735);
DISPLAY 0.680851 (-2635 1735);
PAINT MONO (-2635 1735);
FORCEPROP 0 LASTPIN (-2625 875) $PN 86
J 2
(-2635 885);
DISPLAY 0.680851 (-2635 885);
PAINT MONO (-2635 885);
FORCEPROP 0 LASTPIN (-2625 825) $PN 87
J 2
(-2635 835);
DISPLAY 0.680851 (-2635 835);
PAINT MONO (-2635 835);
FORCEPROP 0 LASTPIN (-2625 3475) $PN 74
J 2
(-2635 3485);
DISPLAY 0.680851 (-2635 3485);
PAINT MONO (-2635 3485);
FORCEPROP 0 LASTPIN (-2625 3425) $PN 227
J 2
(-2635 3435);
DISPLAY 0.680851 (-2635 3435);
PAINT MONO (-2635 3435);
FORCEPROP 0 LASTPIN (-2625 1425) $PN 147
J 2
(-2635 1435);
DISPLAY 0.680851 (-2635 1435);
PAINT MONO (-2635 1435);
FORCEPROP 0 LASTPIN (-2625 1975) $PN 207
J 2
(-2635 1985);
DISPLAY 0.680851 (-2635 1985);
PAINT MONO (-2635 1985);
FORCEPROP 0 LASTPIN (-2625 1025) $PN 2
J 2
(-2635 1035);
DISPLAY 0.680851 (-2635 1035);
PAINT MONO (-2635 1035);
FORCEPROP 0 LASTPIN (-2625 1075) $PN 144
J 2
(-2635 1085);
DISPLAY 0.680851 (-2635 1085);
PAINT MONO (-2635 1085);
FORCEPROP 0 LASTPIN (-2625 1125) $PN 149
J 2
(-2635 1135);
DISPLAY 0.680851 (-2635 1135);
PAINT MONO (-2635 1135);
FORCEPROP 0 LASTPIN (-2625 1175) $PN 150
J 2
(-2635 1185);
DISPLAY 0.680851 (-2635 1185);
PAINT MONO (-2635 1185);
FORCEPROP 0 LASTPIN (-2625 1225) $PN 220
J 2
(-2635 1235);
DISPLAY 0.680851 (-2635 1235);
PAINT MONO (-2635 1235);
FORCEPROP 0 LASTPIN (-2625 1275) $PN 231
J 2
(-2635 1285);
DISPLAY 0.680851 (-2635 1285);
PAINT MONO (-2635 1285);
FORCEPROP 0 LASTPIN (-2625 1325) $PN 232
J 2
(-2635 1335);
DISPLAY 0.680851 (-2635 1335);
PAINT MONO (-2635 1335);
FORCEPROP 0 LASTPIN (-2625 1825) $PN 3
J 2
(-2635 1835);
DISPLAY 0.680851 (-2635 1835);
PAINT MONO (-2635 1835);
FORCEPROP 1 LAST NEEDS_NO_SIZE TRUE
J 0
(-2025 2550);
DISPLAY 0.723404 (-2025 2550);
PAINT GREEN (-2025 2550);
DISPLAY INVISIBLE (-2025 2550);
FORCEPROP 1 LAST CDS_LMAN_SYM_OUTLINE -450,1875,450,-1875
J 0
(-2025 2550);
DISPLAY 0.468085 (-2025 2550);
PAINT GREEN (-2025 2550);
DISPLAY INVISIBLE (-2025 2550);
FORCEPROP 2 LAST CDS_LIB pure_quanta
J 0
(-2025 2550);
DISPLAY INVISIBLE (-2025 2550);
FORCEPROP 1 LAST PATH I178
J 0
(-2025 2550);
DISPLAY 0.723404 (-2025 2550);
PAINT GREEN (-2025 2550);
DISPLAY INVISIBLE (-2025 2550);
FORCEPROP 2 LAST CDS_LOCATION J24
J 0
(-2475 4775);
DISPLAY 1.021277 (-2475 4775);
DISPLAY INVISIBLE (-2475 4775);
FORCEPROP 0 LAST $SEC 1
J 0
(-2475 4775);
DISPLAY 0.680851 (-2475 4775);
PAINT MONO (-2475 4775);
DISPLAY INVISIBLE (-2475 4775);
FORCEPROP 2 LAST CDS_SEC 1
J 0
(-2475 4775);
DISPLAY 1.021277 (-2475 4775);
DISPLAY INVISIBLE (-2475 4775);
FORCEADD OFFPAGE..1
(-3775 3025);
FORCEPROP 2 LAST $XR0 54 
J 0
(-3996 3025);
DISPLAY 0.638298 (-3996 3025);
PAINT MONO (-3996 3025);
FORCEPROP 2 LAST CDS_LIB standard
J 0
(-3775 3025);
PAINT MONO (-3775 3025);
DISPLAY INVISIBLE (-3775 3025);
FORCEPROP 1 LAST OFFPAGE TRUE
J 0
(-3450 2900);
DISPLAY 0.872340 (-3450 2900);
DISPLAY INVISIBLE (-3450 2900);
FORCEPROP 1 LAST COMMENT_BODY TRUE
J 0
(-3650 2925);
DISPLAY 0.872340 (-3650 2925);
PAINT GREEN (-3650 2925);
DISPLAY INVISIBLE (-3650 2925);
FORCEPROP 2 LAST PATH I18
J 0
(-3725 3100);
DISPLAY 1.021277 (-3725 3100);
DISPLAY INVISIBLE (-3725 3100);
FORCEADD SCONN288_ADR50017P087CC..3
(4075 2650);
FORCEPROP 1 LAST PART_NUMBER DFHST8FS460
J 0
(3620 4574);
DISPLAY 0.723404 (3620 4574);
PAINT GREEN (3620 4574);
DISPLAY INVISIBLE (3620 4574);
FORCEPROP 2 LAST PART_TYPE SMLF
J 0
(3625 4725);
DISPLAY 1.021277 (3625 4725);
FORCEPROP 1 LAST MATERIAL IO
J 0
(3620 4447);
DISPLAY 0.723404 (3620 4447);
PAINT GREEN (3620 4447);
FORCEPROP 2 LAST VALUE SCONN288_ADR50017-P087CC
J 0
(3625 4675);
DISPLAY 1.021277 (3625 4675);
FORCEPROP 1 LAST $LOCATION J24
J 0
(3625 4625);
DISPLAY 0.723404 (3625 4625);
PAINT GREEN (3625 4625);
FORCEPROP 0 LASTPIN (4675 1025) $PN G1
J 0
(4685 1035);
DISPLAY 0.680851 (4685 1035);
PAINT MONO (4685 1035);
FORCEPROP 0 LASTPIN (4675 975) $PN G2
J 0
(4685 985);
DISPLAY 0.680851 (4685 985);
PAINT MONO (4685 985);
FORCEPROP 0 LASTPIN (4675 925) $PN G3
J 0
(4685 935);
DISPLAY 0.680851 (4685 935);
PAINT MONO (4685 935);
FORCEPROP 0 LASTPIN (3475 4175) $PN 1
J 2
(3465 4185);
DISPLAY 0.680851 (3465 4185);
PAINT MONO (3465 4185);
FORCEPROP 0 LASTPIN (3475 4225) $PN 145
J 2
(3465 4235);
DISPLAY 0.680851 (3465 4235);
PAINT MONO (3465 4235);
FORCEPROP 0 LASTPIN (3475 4275) $PN 146
J 2
(3465 4285);
DISPLAY 0.680851 (3465 4285);
PAINT MONO (3465 4285);
FORCEPROP 0 LASTPIN (4675 1125) $PN 6
J 0
(4685 1135);
DISPLAY 0.680851 (4685 1135);
PAINT MONO (4685 1135);
FORCEPROP 0 LASTPIN (4675 1175) $PN 8
J 0
(4685 1185);
DISPLAY 0.680851 (4685 1185);
PAINT MONO (4685 1185);
FORCEPROP 0 LASTPIN (4675 1225) $PN 10
J 0
(4685 1235);
DISPLAY 0.680851 (4685 1235);
PAINT MONO (4685 1235);
FORCEPROP 0 LASTPIN (4675 1275) $PN 13
J 0
(4685 1285);
DISPLAY 0.680851 (4685 1285);
PAINT MONO (4685 1285);
FORCEPROP 0 LASTPIN (4675 1325) $PN 15
J 0
(4685 1335);
DISPLAY 0.680851 (4685 1335);
PAINT MONO (4685 1335);
FORCEPROP 0 LASTPIN (4675 1375) $PN 17
J 0
(4685 1385);
DISPLAY 0.680851 (4685 1385);
PAINT MONO (4685 1385);
FORCEPROP 0 LASTPIN (4675 1425) $PN 19
J 0
(4685 1435);
DISPLAY 0.680851 (4685 1435);
PAINT MONO (4685 1435);
FORCEPROP 0 LASTPIN (4675 1475) $PN 21
J 0
(4685 1485);
DISPLAY 0.680851 (4685 1485);
PAINT MONO (4685 1485);
FORCEPROP 0 LASTPIN (4675 1525) $PN 24
J 0
(4685 1535);
DISPLAY 0.680851 (4685 1535);
PAINT MONO (4685 1535);
FORCEPROP 0 LASTPIN (4675 1575) $PN 26
J 0
(4685 1585);
DISPLAY 0.680851 (4685 1585);
PAINT MONO (4685 1585);
FORCEPROP 0 LASTPIN (4675 1625) $PN 28
J 0
(4685 1635);
DISPLAY 0.680851 (4685 1635);
PAINT MONO (4685 1635);
FORCEPROP 0 LASTPIN (4675 1675) $PN 30
J 0
(4685 1685);
DISPLAY 0.680851 (4685 1685);
PAINT MONO (4685 1685);
FORCEPROP 0 LASTPIN (4675 1725) $PN 32
J 0
(4685 1735);
DISPLAY 0.680851 (4685 1735);
PAINT MONO (4685 1735);
FORCEPROP 0 LASTPIN (4675 1775) $PN 35
J 0
(4685 1785);
DISPLAY 0.680851 (4685 1785);
PAINT MONO (4685 1785);
FORCEPROP 0 LASTPIN (4675 1825) $PN 37
J 0
(4685 1835);
DISPLAY 0.680851 (4685 1835);
PAINT MONO (4685 1835);
FORCEPROP 0 LASTPIN (4675 1875) $PN 39
J 0
(4685 1885);
DISPLAY 0.680851 (4685 1885);
PAINT MONO (4685 1885);
FORCEPROP 0 LASTPIN (4675 1925) $PN 41
J 0
(4685 1935);
DISPLAY 0.680851 (4685 1935);
PAINT MONO (4685 1935);
FORCEPROP 0 LASTPIN (4675 1975) $PN 43
J 0
(4685 1985);
DISPLAY 0.680851 (4685 1985);
PAINT MONO (4685 1985);
FORCEPROP 0 LASTPIN (4675 2025) $PN 46
J 0
(4685 2035);
DISPLAY 0.680851 (4685 2035);
PAINT MONO (4685 2035);
FORCEPROP 0 LASTPIN (4675 2075) $PN 48
J 0
(4685 2085);
DISPLAY 0.680851 (4685 2085);
PAINT MONO (4685 2085);
FORCEPROP 0 LASTPIN (4675 2125) $PN 50
J 0
(4685 2135);
DISPLAY 0.680851 (4685 2135);
PAINT MONO (4685 2135);
FORCEPROP 0 LASTPIN (4675 2175) $PN 52
J 0
(4685 2185);
DISPLAY 0.680851 (4685 2185);
PAINT MONO (4685 2185);
FORCEPROP 0 LASTPIN (4675 2225) $PN 54
J 0
(4685 2235);
DISPLAY 0.680851 (4685 2235);
PAINT MONO (4685 2235);
FORCEPROP 0 LASTPIN (4675 2275) $PN 57
J 0
(4685 2285);
DISPLAY 0.680851 (4685 2285);
PAINT MONO (4685 2285);
FORCEPROP 0 LASTPIN (4675 2325) $PN 59
J 0
(4685 2335);
DISPLAY 0.680851 (4685 2335);
PAINT MONO (4685 2335);
FORCEPROP 0 LASTPIN (4675 2375) $PN 61
J 0
(4685 2385);
DISPLAY 0.680851 (4685 2385);
PAINT MONO (4685 2385);
FORCEPROP 0 LASTPIN (4675 2425) $PN 63
J 0
(4685 2435);
DISPLAY 0.680851 (4685 2435);
PAINT MONO (4685 2435);
FORCEPROP 0 LASTPIN (4675 2475) $PN 65
J 0
(4685 2485);
DISPLAY 0.680851 (4685 2485);
PAINT MONO (4685 2485);
FORCEPROP 0 LASTPIN (4675 2525) $PN 67
J 0
(4685 2535);
DISPLAY 0.680851 (4685 2535);
PAINT MONO (4685 2535);
FORCEPROP 0 LASTPIN (4675 2575) $PN 69
J 0
(4685 2585);
DISPLAY 0.680851 (4685 2585);
PAINT MONO (4685 2585);
FORCEPROP 0 LASTPIN (4675 2625) $PN 71
J 0
(4685 2635);
DISPLAY 0.680851 (4685 2635);
PAINT MONO (4685 2635);
FORCEPROP 0 LASTPIN (4675 2675) $PN 73
J 0
(4685 2685);
DISPLAY 0.680851 (4685 2685);
PAINT MONO (4685 2685);
FORCEPROP 0 LASTPIN (4675 2725) $PN 75
J 0
(4685 2735);
DISPLAY 0.680851 (4685 2735);
PAINT MONO (4685 2735);
FORCEPROP 0 LASTPIN (4675 2775) $PN 77
J 0
(4685 2785);
DISPLAY 0.680851 (4685 2785);
PAINT MONO (4685 2785);
FORCEPROP 0 LASTPIN (4675 2825) $PN 79
J 0
(4685 2835);
DISPLAY 0.680851 (4685 2835);
PAINT MONO (4685 2835);
FORCEPROP 0 LASTPIN (4675 2875) $PN 81
J 0
(4685 2885);
DISPLAY 0.680851 (4685 2885);
PAINT MONO (4685 2885);
FORCEPROP 0 LASTPIN (4675 2925) $PN 83
J 0
(4685 2935);
DISPLAY 0.680851 (4685 2935);
PAINT MONO (4685 2935);
FORCEPROP 0 LASTPIN (4675 2975) $PN 85
J 0
(4685 2985);
DISPLAY 0.680851 (4685 2985);
PAINT MONO (4685 2985);
FORCEPROP 0 LASTPIN (4675 3025) $PN 88
J 0
(4685 3035);
DISPLAY 0.680851 (4685 3035);
PAINT MONO (4685 3035);
FORCEPROP 0 LASTPIN (4675 3075) $PN 90
J 0
(4685 3085);
DISPLAY 0.680851 (4685 3085);
PAINT MONO (4685 3085);
FORCEPROP 0 LASTPIN (4675 3125) $PN 92
J 0
(4685 3135);
DISPLAY 0.680851 (4685 3135);
PAINT MONO (4685 3135);
FORCEPROP 0 LASTPIN (4675 3175) $PN 95
J 0
(4685 3185);
DISPLAY 0.680851 (4685 3185);
PAINT MONO (4685 3185);
FORCEPROP 0 LASTPIN (4675 3225) $PN 97
J 0
(4685 3235);
DISPLAY 0.680851 (4685 3235);
PAINT MONO (4685 3235);
FORCEPROP 0 LASTPIN (4675 3275) $PN 99
J 0
(4685 3285);
DISPLAY 0.680851 (4685 3285);
PAINT MONO (4685 3285);
FORCEPROP 0 LASTPIN (4675 3325) $PN 101
J 0
(4685 3335);
DISPLAY 0.680851 (4685 3335);
PAINT MONO (4685 3335);
FORCEPROP 0 LASTPIN (4675 3375) $PN 103
J 0
(4685 3385);
DISPLAY 0.680851 (4685 3385);
PAINT MONO (4685 3385);
FORCEPROP 0 LASTPIN (4675 3425) $PN 106
J 0
(4685 3435);
DISPLAY 0.680851 (4685 3435);
PAINT MONO (4685 3435);
FORCEPROP 0 LASTPIN (4675 3475) $PN 108
J 0
(4685 3485);
DISPLAY 0.680851 (4685 3485);
PAINT MONO (4685 3485);
FORCEPROP 0 LASTPIN (4675 3525) $PN 110
J 0
(4685 3535);
DISPLAY 0.680851 (4685 3535);
PAINT MONO (4685 3535);
FORCEPROP 0 LASTPIN (4675 3575) $PN 112
J 0
(4685 3585);
DISPLAY 0.680851 (4685 3585);
PAINT MONO (4685 3585);
FORCEPROP 0 LASTPIN (4675 3625) $PN 114
J 0
(4685 3635);
DISPLAY 0.680851 (4685 3635);
PAINT MONO (4685 3635);
FORCEPROP 0 LASTPIN (4675 3675) $PN 117
J 0
(4685 3685);
DISPLAY 0.680851 (4685 3685);
PAINT MONO (4685 3685);
FORCEPROP 0 LASTPIN (4675 3725) $PN 119
J 0
(4685 3735);
DISPLAY 0.680851 (4685 3735);
PAINT MONO (4685 3735);
FORCEPROP 0 LASTPIN (4675 3775) $PN 121
J 0
(4685 3785);
DISPLAY 0.680851 (4685 3785);
PAINT MONO (4685 3785);
FORCEPROP 0 LASTPIN (4675 3825) $PN 123
J 0
(4685 3835);
DISPLAY 0.680851 (4685 3835);
PAINT MONO (4685 3835);
FORCEPROP 0 LASTPIN (4675 3875) $PN 125
J 0
(4685 3885);
DISPLAY 0.680851 (4685 3885);
PAINT MONO (4685 3885);
FORCEPROP 0 LASTPIN (4675 3925) $PN 128
J 0
(4685 3935);
DISPLAY 0.680851 (4685 3935);
PAINT MONO (4685 3935);
FORCEPROP 0 LASTPIN (4675 3975) $PN 130
J 0
(4685 3985);
DISPLAY 0.680851 (4685 3985);
PAINT MONO (4685 3985);
FORCEPROP 0 LASTPIN (4675 4025) $PN 132
J 0
(4685 4035);
DISPLAY 0.680851 (4685 4035);
PAINT MONO (4685 4035);
FORCEPROP 0 LASTPIN (4675 4075) $PN 134
J 0
(4685 4085);
DISPLAY 0.680851 (4685 4085);
PAINT MONO (4685 4085);
FORCEPROP 0 LASTPIN (4675 4125) $PN 136
J 0
(4685 4135);
DISPLAY 0.680851 (4685 4135);
PAINT MONO (4685 4135);
FORCEPROP 0 LASTPIN (4675 4175) $PN 139
J 0
(4685 4185);
DISPLAY 0.680851 (4685 4185);
PAINT MONO (4685 4185);
FORCEPROP 0 LASTPIN (4675 4225) $PN 141
J 0
(4685 4235);
DISPLAY 0.680851 (4685 4235);
PAINT MONO (4685 4235);
FORCEPROP 0 LASTPIN (4675 4275) $PN 143
J 0
(4685 4285);
DISPLAY 0.680851 (4685 4285);
PAINT MONO (4685 4285);
FORCEPROP 0 LASTPIN (3475 1025) $PN 151
J 2
(3465 1035);
DISPLAY 0.680851 (3465 1035);
PAINT MONO (3465 1035);
FORCEPROP 0 LASTPIN (3475 1075) $PN 153
J 2
(3465 1085);
DISPLAY 0.680851 (3465 1085);
PAINT MONO (3465 1085);
FORCEPROP 0 LASTPIN (3475 1125) $PN 155
J 2
(3465 1135);
DISPLAY 0.680851 (3465 1135);
PAINT MONO (3465 1135);
FORCEPROP 0 LASTPIN (3475 1175) $PN 158
J 2
(3465 1185);
DISPLAY 0.680851 (3465 1185);
PAINT MONO (3465 1185);
FORCEPROP 0 LASTPIN (3475 1225) $PN 160
J 2
(3465 1235);
DISPLAY 0.680851 (3465 1235);
PAINT MONO (3465 1235);
FORCEPROP 0 LASTPIN (3475 1275) $PN 162
J 2
(3465 1285);
DISPLAY 0.680851 (3465 1285);
PAINT MONO (3465 1285);
FORCEPROP 0 LASTPIN (3475 1325) $PN 164
J 2
(3465 1335);
DISPLAY 0.680851 (3465 1335);
PAINT MONO (3465 1335);
FORCEPROP 0 LASTPIN (3475 1375) $PN 166
J 2
(3465 1385);
DISPLAY 0.680851 (3465 1385);
PAINT MONO (3465 1385);
FORCEPROP 0 LASTPIN (3475 1425) $PN 169
J 2
(3465 1435);
DISPLAY 0.680851 (3465 1435);
PAINT MONO (3465 1435);
FORCEPROP 0 LASTPIN (3475 1475) $PN 171
J 2
(3465 1485);
DISPLAY 0.680851 (3465 1485);
PAINT MONO (3465 1485);
FORCEPROP 0 LASTPIN (3475 1525) $PN 173
J 2
(3465 1535);
DISPLAY 0.680851 (3465 1535);
PAINT MONO (3465 1535);
FORCEPROP 0 LASTPIN (3475 1575) $PN 175
J 2
(3465 1585);
DISPLAY 0.680851 (3465 1585);
PAINT MONO (3465 1585);
FORCEPROP 0 LASTPIN (3475 1625) $PN 177
J 2
(3465 1635);
DISPLAY 0.680851 (3465 1635);
PAINT MONO (3465 1635);
FORCEPROP 0 LASTPIN (3475 1675) $PN 180
J 2
(3465 1685);
DISPLAY 0.680851 (3465 1685);
PAINT MONO (3465 1685);
FORCEPROP 0 LASTPIN (3475 1725) $PN 182
J 2
(3465 1735);
DISPLAY 0.680851 (3465 1735);
PAINT MONO (3465 1735);
FORCEPROP 0 LASTPIN (3475 1775) $PN 184
J 2
(3465 1785);
DISPLAY 0.680851 (3465 1785);
PAINT MONO (3465 1785);
FORCEPROP 0 LASTPIN (3475 1825) $PN 186
J 2
(3465 1835);
DISPLAY 0.680851 (3465 1835);
PAINT MONO (3465 1835);
FORCEPROP 0 LASTPIN (3475 1875) $PN 188
J 2
(3465 1885);
DISPLAY 0.680851 (3465 1885);
PAINT MONO (3465 1885);
FORCEPROP 0 LASTPIN (3475 1925) $PN 191
J 2
(3465 1935);
DISPLAY 0.680851 (3465 1935);
PAINT MONO (3465 1935);
FORCEPROP 0 LASTPIN (3475 1975) $PN 193
J 2
(3465 1985);
DISPLAY 0.680851 (3465 1985);
PAINT MONO (3465 1985);
FORCEPROP 0 LASTPIN (3475 2025) $PN 195
J 2
(3465 2035);
DISPLAY 0.680851 (3465 2035);
PAINT MONO (3465 2035);
FORCEPROP 0 LASTPIN (3475 2075) $PN 197
J 2
(3465 2085);
DISPLAY 0.680851 (3465 2085);
PAINT MONO (3465 2085);
FORCEPROP 0 LASTPIN (3475 2125) $PN 199
J 2
(3465 2135);
DISPLAY 0.680851 (3465 2135);
PAINT MONO (3465 2135);
FORCEPROP 0 LASTPIN (3475 2175) $PN 202
J 2
(3465 2185);
DISPLAY 0.680851 (3465 2185);
PAINT MONO (3465 2185);
FORCEPROP 0 LASTPIN (3475 2225) $PN 204
J 2
(3465 2235);
DISPLAY 0.680851 (3465 2235);
PAINT MONO (3465 2235);
FORCEPROP 0 LASTPIN (3475 2275) $PN 206
J 2
(3465 2285);
DISPLAY 0.680851 (3465 2285);
PAINT MONO (3465 2285);
FORCEPROP 0 LASTPIN (3475 2325) $PN 208
J 2
(3465 2335);
DISPLAY 0.680851 (3465 2335);
PAINT MONO (3465 2335);
FORCEPROP 0 LASTPIN (3475 2375) $PN 210
J 2
(3465 2385);
DISPLAY 0.680851 (3465 2385);
PAINT MONO (3465 2385);
FORCEPROP 0 LASTPIN (3475 2425) $PN 212
J 2
(3465 2435);
DISPLAY 0.680851 (3465 2435);
PAINT MONO (3465 2435);
FORCEPROP 0 LASTPIN (3475 2475) $PN 214
J 2
(3465 2485);
DISPLAY 0.680851 (3465 2485);
PAINT MONO (3465 2485);
FORCEPROP 0 LASTPIN (3475 2525) $PN 216
J 2
(3465 2535);
DISPLAY 0.680851 (3465 2535);
PAINT MONO (3465 2535);
FORCEPROP 0 LASTPIN (3475 2575) $PN 219
J 2
(3465 2585);
DISPLAY 0.680851 (3465 2585);
PAINT MONO (3465 2585);
FORCEPROP 0 LASTPIN (3475 2625) $PN 222
J 2
(3465 2635);
DISPLAY 0.680851 (3465 2635);
PAINT MONO (3465 2635);
FORCEPROP 0 LASTPIN (3475 2675) $PN 224
J 2
(3465 2685);
DISPLAY 0.680851 (3465 2685);
PAINT MONO (3465 2685);
FORCEPROP 0 LASTPIN (3475 2725) $PN 226
J 2
(3465 2735);
DISPLAY 0.680851 (3465 2735);
PAINT MONO (3465 2735);
FORCEPROP 0 LASTPIN (3475 2775) $PN 228
J 2
(3465 2785);
DISPLAY 0.680851 (3465 2785);
PAINT MONO (3465 2785);
FORCEPROP 0 LASTPIN (3475 2825) $PN 230
J 2
(3465 2835);
DISPLAY 0.680851 (3465 2835);
PAINT MONO (3465 2835);
FORCEPROP 0 LASTPIN (3475 2875) $PN 233
J 2
(3465 2885);
DISPLAY 0.680851 (3465 2885);
PAINT MONO (3465 2885);
FORCEPROP 0 LASTPIN (3475 2925) $PN 235
J 2
(3465 2935);
DISPLAY 0.680851 (3465 2935);
PAINT MONO (3465 2935);
FORCEPROP 0 LASTPIN (3475 2975) $PN 237
J 2
(3465 2985);
DISPLAY 0.680851 (3465 2985);
PAINT MONO (3465 2985);
FORCEPROP 0 LASTPIN (3475 3025) $PN 240
J 2
(3465 3035);
DISPLAY 0.680851 (3465 3035);
PAINT MONO (3465 3035);
FORCEPROP 0 LASTPIN (3475 3075) $PN 242
J 2
(3465 3085);
DISPLAY 0.680851 (3465 3085);
PAINT MONO (3465 3085);
FORCEPROP 0 LASTPIN (3475 3125) $PN 244
J 2
(3465 3135);
DISPLAY 0.680851 (3465 3135);
PAINT MONO (3465 3135);
FORCEPROP 0 LASTPIN (3475 3175) $PN 246
J 2
(3465 3185);
DISPLAY 0.680851 (3465 3185);
PAINT MONO (3465 3185);
FORCEPROP 0 LASTPIN (3475 3225) $PN 248
J 2
(3465 3235);
DISPLAY 0.680851 (3465 3235);
PAINT MONO (3465 3235);
FORCEPROP 0 LASTPIN (3475 3275) $PN 251
J 2
(3465 3285);
DISPLAY 0.680851 (3465 3285);
PAINT MONO (3465 3285);
FORCEPROP 0 LASTPIN (3475 3325) $PN 253
J 2
(3465 3335);
DISPLAY 0.680851 (3465 3335);
PAINT MONO (3465 3335);
FORCEPROP 0 LASTPIN (3475 3375) $PN 255
J 2
(3465 3385);
DISPLAY 0.680851 (3465 3385);
PAINT MONO (3465 3385);
FORCEPROP 0 LASTPIN (3475 3425) $PN 257
J 2
(3465 3435);
DISPLAY 0.680851 (3465 3435);
PAINT MONO (3465 3435);
FORCEPROP 0 LASTPIN (3475 3475) $PN 259
J 2
(3465 3485);
DISPLAY 0.680851 (3465 3485);
PAINT MONO (3465 3485);
FORCEPROP 0 LASTPIN (3475 3525) $PN 262
J 2
(3465 3535);
DISPLAY 0.680851 (3465 3535);
PAINT MONO (3465 3535);
FORCEPROP 0 LASTPIN (3475 3575) $PN 264
J 2
(3465 3585);
DISPLAY 0.680851 (3465 3585);
PAINT MONO (3465 3585);
FORCEPROP 0 LASTPIN (3475 3625) $PN 266
J 2
(3465 3635);
DISPLAY 0.680851 (3465 3635);
PAINT MONO (3465 3635);
FORCEPROP 0 LASTPIN (3475 3675) $PN 268
J 2
(3465 3685);
DISPLAY 0.680851 (3465 3685);
PAINT MONO (3465 3685);
FORCEPROP 0 LASTPIN (3475 3725) $PN 270
J 2
(3465 3735);
DISPLAY 0.680851 (3465 3735);
PAINT MONO (3465 3735);
FORCEPROP 0 LASTPIN (3475 3775) $PN 273
J 2
(3465 3785);
DISPLAY 0.680851 (3465 3785);
PAINT MONO (3465 3785);
FORCEPROP 0 LASTPIN (3475 3825) $PN 275
J 2
(3465 3835);
DISPLAY 0.680851 (3465 3835);
PAINT MONO (3465 3835);
FORCEPROP 0 LASTPIN (3475 3875) $PN 277
J 2
(3465 3885);
DISPLAY 0.680851 (3465 3885);
PAINT MONO (3465 3885);
FORCEPROP 0 LASTPIN (3475 3925) $PN 279
J 2
(3465 3935);
DISPLAY 0.680851 (3465 3935);
PAINT MONO (3465 3935);
FORCEPROP 0 LASTPIN (3475 3975) $PN 281
J 2
(3465 3985);
DISPLAY 0.680851 (3465 3985);
PAINT MONO (3465 3985);
FORCEPROP 0 LASTPIN (3475 4025) $PN 284
J 2
(3465 4035);
DISPLAY 0.680851 (3465 4035);
PAINT MONO (3465 4035);
FORCEPROP 0 LASTPIN (3475 4075) $PN 286
J 2
(3465 4085);
DISPLAY 0.680851 (3465 4085);
PAINT MONO (3465 4085);
FORCEPROP 0 LASTPIN (3475 4125) $PN 288
J 2
(3465 4135);
DISPLAY 0.680851 (3465 4135);
PAINT MONO (3465 4135);
FORCEPROP 1 LAST NEEDS_NO_SIZE TRUE
J 0
(4075 2650);
DISPLAY 0.723404 (4075 2650);
PAINT GREEN (4075 2650);
DISPLAY INVISIBLE (4075 2650);
FORCEPROP 1 LAST CDS_LMAN_SYM_OUTLINE -450,1775,450,-1775
J 0
(4075 2650);
DISPLAY 0.468085 (4075 2650);
PAINT GREEN (4075 2650);
DISPLAY INVISIBLE (4075 2650);
FORCEPROP 2 LAST CDS_LIB pure_quanta
J 0
(4075 2650);
DISPLAY INVISIBLE (4075 2650);
FORCEPROP 1 LAST PATH I180
J 0
(4075 2650);
DISPLAY 0.723404 (4075 2650);
PAINT GREEN (4075 2650);
DISPLAY INVISIBLE (4075 2650);
FORCEPROP 2 LAST CDS_LOCATION J24
J 0
(3625 4775);
DISPLAY 1.021277 (3625 4775);
DISPLAY INVISIBLE (3625 4775);
FORCEPROP 0 LAST $SEC 3
J 0
(3625 4775);
DISPLAY 0.680851 (3625 4775);
PAINT MONO (3625 4775);
DISPLAY INVISIBLE (3625 4775);
FORCEPROP 2 LAST CDS_SEC 3
J 0
(3625 4775);
DISPLAY 1.021277 (3625 4775);
DISPLAY INVISIBLE (3625 4775);
FORCEADD SCONN288_ADR50017P087CC..2
(650 3275);
FORCEPROP 1 LAST PART_NUMBER DFHST8FS460
J 0
(45 4563);
DISPLAY 0.723404 (45 4563);
PAINT GREEN (45 4563);
DISPLAY INVISIBLE (45 4563);
FORCEPROP 2 LAST PART_TYPE SMLF
J 0
(50 4800);
DISPLAY 1.021277 (50 4800);
FORCEPROP 1 LAST MATERIAL IO
J 0
(45 4436);
DISPLAY 0.723404 (45 4436);
PAINT GREEN (45 4436);
FORCEPROP 2 LAST VALUE SCONN288_ADR50017-P087CC
J 0
(50 4750);
DISPLAY 1.021277 (50 4750);
FORCEPROP 1 LAST LOCATION J24
J 0
(45 4710);
DISPLAY 0.723404 (45 4710);
PAINT GREEN (45 4710);
FORCEPROP 0 LASTPIN (1400 3325) $PN 12
J 0
(1410 3335);
DISPLAY 0.680851 (1410 3335);
PAINT MONO (1410 3335);
FORCEPROP 0 LASTPIN (1400 3375) $PN 11
J 0
(1410 3385);
DISPLAY 0.680851 (1410 3385);
PAINT MONO (1410 3385);
FORCEPROP 0 LASTPIN (1400 2275) $PN 105
J 0
(1410 2285);
DISPLAY 0.680851 (1410 2285);
PAINT MONO (1410 2285);
FORCEPROP 0 LASTPIN (1400 2325) $PN 104
J 0
(1410 2335);
DISPLAY 0.680851 (1410 2335);
PAINT MONO (1410 2335);
FORCEPROP 0 LASTPIN (1400 3425) $PN 23
J 0
(1410 3435);
DISPLAY 0.680851 (1410 3435);
PAINT MONO (1410 3435);
FORCEPROP 0 LASTPIN (1400 3475) $PN 22
J 0
(1410 3485);
DISPLAY 0.680851 (1410 3485);
PAINT MONO (1410 3485);
FORCEPROP 0 LASTPIN (1400 2375) $PN 116
J 0
(1410 2385);
DISPLAY 0.680851 (1410 2385);
PAINT MONO (1410 2385);
FORCEPROP 0 LASTPIN (1400 2425) $PN 115
J 0
(1410 2435);
DISPLAY 0.680851 (1410 2435);
PAINT MONO (1410 2435);
FORCEPROP 0 LASTPIN (1400 3525) $PN 34
J 0
(1410 3535);
DISPLAY 0.680851 (1410 3535);
PAINT MONO (1410 3535);
FORCEPROP 0 LASTPIN (1400 3575) $PN 33
J 0
(1410 3585);
DISPLAY 0.680851 (1410 3585);
PAINT MONO (1410 3585);
FORCEPROP 0 LASTPIN (1400 2475) $PN 127
J 0
(1410 2485);
DISPLAY 0.680851 (1410 2485);
PAINT MONO (1410 2485);
FORCEPROP 0 LASTPIN (1400 2525) $PN 126
J 0
(1410 2535);
DISPLAY 0.680851 (1410 2535);
PAINT MONO (1410 2535);
FORCEPROP 0 LASTPIN (1400 3625) $PN 45
J 0
(1410 3635);
DISPLAY 0.680851 (1410 3635);
PAINT MONO (1410 3635);
FORCEPROP 0 LASTPIN (1400 3675) $PN 44
J 0
(1410 3685);
DISPLAY 0.680851 (1410 3685);
PAINT MONO (1410 3685);
FORCEPROP 0 LASTPIN (1400 2575) $PN 138
J 0
(1410 2585);
DISPLAY 0.680851 (1410 2585);
PAINT MONO (1410 2585);
FORCEPROP 0 LASTPIN (1400 2625) $PN 137
J 0
(1410 2635);
DISPLAY 0.680851 (1410 2635);
PAINT MONO (1410 2635);
FORCEPROP 0 LASTPIN (1400 3725) $PN 56
J 0
(1410 3735);
DISPLAY 0.680851 (1410 3735);
PAINT MONO (1410 3735);
FORCEPROP 0 LASTPIN (1400 3775) $PN 55
J 0
(1410 3785);
DISPLAY 0.680851 (1410 3785);
PAINT MONO (1410 3785);
FORCEPROP 0 LASTPIN (1400 2675) $PN 238
J 0
(1410 2685);
DISPLAY 0.680851 (1410 2685);
PAINT MONO (1410 2685);
FORCEPROP 0 LASTPIN (1400 2725) $PN 239
J 0
(1410 2735);
DISPLAY 0.680851 (1410 2735);
PAINT MONO (1410 2735);
FORCEPROP 0 LASTPIN (1400 3825) $PN 156
J 0
(1410 3835);
DISPLAY 0.680851 (1410 3835);
PAINT MONO (1410 3835);
FORCEPROP 0 LASTPIN (1400 3875) $PN 157
J 0
(1410 3885);
DISPLAY 0.680851 (1410 3885);
PAINT MONO (1410 3885);
FORCEPROP 0 LASTPIN (1400 2775) $PN 249
J 0
(1410 2785);
DISPLAY 0.680851 (1410 2785);
PAINT MONO (1410 2785);
FORCEPROP 0 LASTPIN (1400 2825) $PN 250
J 0
(1410 2835);
DISPLAY 0.680851 (1410 2835);
PAINT MONO (1410 2835);
FORCEPROP 0 LASTPIN (1400 3925) $PN 167
J 0
(1410 3935);
DISPLAY 0.680851 (1410 3935);
PAINT MONO (1410 3935);
FORCEPROP 0 LASTPIN (1400 3975) $PN 168
J 0
(1410 3985);
DISPLAY 0.680851 (1410 3985);
PAINT MONO (1410 3985);
FORCEPROP 0 LASTPIN (1400 2875) $PN 260
J 0
(1410 2885);
DISPLAY 0.680851 (1410 2885);
PAINT MONO (1410 2885);
FORCEPROP 0 LASTPIN (1400 2925) $PN 261
J 0
(1410 2935);
DISPLAY 0.680851 (1410 2935);
PAINT MONO (1410 2935);
FORCEPROP 0 LASTPIN (1400 4025) $PN 178
J 0
(1410 4035);
DISPLAY 0.680851 (1410 4035);
PAINT MONO (1410 4035);
FORCEPROP 0 LASTPIN (1400 4075) $PN 179
J 0
(1410 4085);
DISPLAY 0.680851 (1410 4085);
PAINT MONO (1410 4085);
FORCEPROP 0 LASTPIN (1400 2975) $PN 271
J 0
(1410 2985);
DISPLAY 0.680851 (1410 2985);
PAINT MONO (1410 2985);
FORCEPROP 0 LASTPIN (1400 3025) $PN 272
J 0
(1410 3035);
DISPLAY 0.680851 (1410 3035);
PAINT MONO (1410 3035);
FORCEPROP 0 LASTPIN (1400 4125) $PN 189
J 0
(1410 4135);
DISPLAY 0.680851 (1410 4135);
PAINT MONO (1410 4135);
FORCEPROP 0 LASTPIN (1400 4175) $PN 190
J 0
(1410 4185);
DISPLAY 0.680851 (1410 4185);
PAINT MONO (1410 4185);
FORCEPROP 0 LASTPIN (1400 3075) $PN 282
J 0
(1410 3085);
DISPLAY 0.680851 (1410 3085);
PAINT MONO (1410 3085);
FORCEPROP 0 LASTPIN (1400 3125) $PN 283
J 0
(1410 3135);
DISPLAY 0.680851 (1410 3135);
PAINT MONO (1410 3135);
FORCEPROP 0 LASTPIN (1400 4225) $PN 200
J 0
(1410 4235);
DISPLAY 0.680851 (1410 4235);
PAINT MONO (1410 4235);
FORCEPROP 0 LASTPIN (1400 4275) $PN 201
J 0
(1410 4285);
DISPLAY 0.680851 (1410 4285);
PAINT MONO (1410 4285);
FORCEPROP 0 LASTPIN (1400 3175) $PN 94
J 0
(1410 3185);
DISPLAY 0.680851 (1410 3185);
PAINT MONO (1410 3185);
FORCEPROP 0 LASTPIN (1400 3225) $PN 93
J 0
(1410 3235);
DISPLAY 0.680851 (1410 3235);
PAINT MONO (1410 3235);
FORCEPROP 1 LAST NEEDS_NO_SIZE TRUE
J 0
(650 3275);
DISPLAY 0.723404 (650 3275);
PAINT GREEN (650 3275);
DISPLAY INVISIBLE (650 3275);
FORCEPROP 1 LAST CDS_LMAN_SYM_OUTLINE -600,1150,600,-1150
J 0
(650 3275);
DISPLAY 0.468085 (650 3275);
PAINT GREEN (650 3275);
DISPLAY INVISIBLE (650 3275);
FORCEPROP 2 LAST CDS_LIB pure_quanta
J 0
(650 3275);
DISPLAY INVISIBLE (650 3275);
FORCEPROP 1 LAST PATH I181
J 0
(650 3275);
DISPLAY 0.723404 (650 3275);
PAINT GREEN (650 3275);
DISPLAY INVISIBLE (650 3275);
FORCEPROP 0 LAST $SEC 2
J 0
(50 4850);
DISPLAY 0.680851 (50 4850);
PAINT MONO (50 4850);
DISPLAY INVISIBLE (50 4850);
FORCEPROP 0 LAST CDS_SEC 2
J 0
(50 4850);
DISPLAY 1.021277 (50 4850);
DISPLAY INVISIBLE (50 4850);
FORCEADD OFFPAGE..1
(-2625 1525);
FORCEPROP 2 LAST $XR7 104 
J 0
(-3657 1525);
DISPLAY 0.638298 (-3657 1525);
PAINT MONO (-3657 1525);
FORCEPROP 2 LAST $XR6 103 
J 0
(-3537 1525);
DISPLAY 0.638298 (-3537 1525);
PAINT MONO (-3537 1525);
FORCEPROP 2 LAST $XR5 102 
J 0
(-3417 1525);
DISPLAY 0.638298 (-3417 1525);
PAINT MONO (-3417 1525);
FORCEPROP 2 LAST $XR4 101 
J 0
(-3297 1525);
DISPLAY 0.638298 (-3297 1525);
PAINT MONO (-3297 1525);
FORCEPROP 2 LAST $XR3 100 
J 0
(-3177 1525);
DISPLAY 0.638298 (-3177 1525);
PAINT MONO (-3177 1525);
FORCEPROP 2 LAST $XR2 99 
J 0
(-3057 1525);
DISPLAY 0.638298 (-3057 1525);
PAINT MONO (-3057 1525);
FORCEPROP 2 LAST $XR1 98 
J 0
(-2967 1525);
DISPLAY 0.638298 (-2967 1525);
PAINT MONO (-2967 1525);
FORCEPROP 2 LAST $XR0 230 
J 0
(-2877 1525);
DISPLAY 0.638298 (-2877 1525);
PAINT MONO (-2877 1525);
FORCEPROP 2 LAST CDS_LIB standard
J 2
(-2625 1525);
DISPLAY INVISIBLE (-2625 1525);
FORCEPROP 1 LAST OFFPAGE TRUE
J 0
(-2300 1400);
DISPLAY 0.872340 (-2300 1400);
DISPLAY INVISIBLE (-2300 1400);
FORCEPROP 1 LAST COMMENT_BODY TRUE
J 0
(-2500 1425);
DISPLAY 0.872340 (-2500 1425);
PAINT GREEN (-2500 1425);
DISPLAY INVISIBLE (-2500 1425);
FORCEPROP 2 LAST PATH I182
J 2
(-2800 1600);
DISPLAY 1.021277 (-2800 1600);
DISPLAY INVISIBLE (-2800 1600);
FORCEADD Q_RES..1
(-3850 1575);
FORCEPROP 1 LAST PART_NUMBER CS04992FB07
J 0
(-3750 1550);
DISPLAY 0.404255 (-3750 1550);
DISPLAY INVISIBLE (-3750 1550);
FORCEPROP 1 LAST MATERIAL CHIP
J 0
(-4050 1550);
DISPLAY 0.404255 (-4050 1550);
FORCEPROP 1 LAST VALUE 49.9
J 2
(-3625 1575);
DISPLAY 0.510638 (-3625 1575);
FORCEPROP 1 LAST $LOCATION R3898
J 0
(-4075 1575);
DISPLAY 0.638298 (-4075 1575);
FORCEPROP 1 LASTPIN (-3950 1575) $PN 1
J 0
(-3938 1587);
DISPLAY 0.787234 (-3938 1587);
PAINT MONO (-3938 1587);
FORCEPROP 1 LASTPIN (-3750 1575) $PN 2
J 0
(-3788 1587);
DISPLAY 0.787234 (-3788 1587);
PAINT MONO (-3788 1587);
FORCEPROP 2 LAST CDS_LIB pure_quanta
J 0
(-3850 1575);
DISPLAY INVISIBLE (-3850 1575);
FORCEPROP 1 LAST PACK_TYPE 0402LF
J 0
(-3550 1575);
DISPLAY 0.510638 (-3550 1575);
DISPLAY INVISIBLE (-3550 1575);
FORCEPROP 1 LAST TOLERANCE 1%
J 0
(-3625 1575);
DISPLAY 0.510638 (-3625 1575);
DISPLAY INVISIBLE (-3625 1575);
FORCEPROP 1 LAST WATTAGE 1/16W
J 2
(-3550 1525);
DISPLAY 0.404255 (-3550 1525);
DISPLAY INVISIBLE (-3550 1525);
FORCEPROP 1 LAST PATH I183
J 0
(-3900 1725);
DISPLAY 0.978723 (-3900 1725);
PAINT WHITE (-3900 1725);
DISPLAY INVISIBLE (-3900 1725);
FORCEPROP 0 LAST CDS_LOCATION R3898
J 0
(-4000 1625);
DISPLAY 1.021277 (-4000 1625);
DISPLAY INVISIBLE (-4000 1625);
FORCEPROP 0 LAST $SEC 1
J 0
(-4000 1625);
DISPLAY 0.680851 (-4000 1625);
PAINT MONO (-4000 1625);
DISPLAY INVISIBLE (-4000 1625);
FORCEPROP 0 LAST CDS_SEC 1
J 0
(-4000 1625);
DISPLAY 1.021277 (-4000 1625);
DISPLAY INVISIBLE (-4000 1625);
FORCEADD OFFPAGE..1
(-3775 3175);
FORCEPROP 2 LAST $XR0 54 
J 0
(-3996 3175);
DISPLAY 0.638298 (-3996 3175);
PAINT MONO (-3996 3175);
FORCEPROP 2 LAST CDS_LIB standard
J 0
(-3775 3175);
PAINT MONO (-3775 3175);
DISPLAY INVISIBLE (-3775 3175);
FORCEPROP 1 LAST OFFPAGE TRUE
J 0
(-3450 3050);
DISPLAY 0.872340 (-3450 3050);
DISPLAY INVISIBLE (-3450 3050);
FORCEPROP 1 LAST COMMENT_BODY TRUE
J 0
(-3650 3075);
DISPLAY 0.872340 (-3650 3075);
PAINT GREEN (-3650 3075);
DISPLAY INVISIBLE (-3650 3075);
FORCEPROP 2 LAST PATH I19
J 0
(-3725 3250);
DISPLAY 1.021277 (-3725 3250);
DISPLAY INVISIBLE (-3725 3250);
FORCEADD Q_RES..2
(-2625 125);
FORCEPROP 1 LAST PART_NUMBER CS41962FB03
J 0
(-2585 0);
DISPLAY 0.978723 (-2585 0);
DISPLAY INVISIBLE (-2585 0);
FORCEPROP 1 LAST MATERIAL CHIP
J 0
(-2585 50);
DISPLAY 0.978723 (-2585 50);
FORCEPROP 1 LAST TOLERANCE 1%
J 0
(-2580 150);
DISPLAY 0.978723 (-2580 150);
FORCEPROP 1 LAST WATTAGE 1/16W
J 0
(-2585 100);
DISPLAY 0.978723 (-2585 100);
FORCEPROP 1 LAST PACK_TYPE 0402LF
J 0
(-2585 -50);
DISPLAY 0.978723 (-2585 -50);
FORCEPROP 1 LAST VALUE 196K
J 0
(-2580 200);
DISPLAY 0.978723 (-2580 200);
FORCEPROP 1 LAST $LOCATION R80
J 0
(-2580 250);
DISPLAY 0.978723 (-2580 250);
FORCEPROP 1 LASTPIN (-2625 225) $PN 1
J 0
(-2620 187);
DISPLAY 0.787234 (-2620 187);
FORCEPROP 1 LASTPIN (-2625 25) $PN 2
J 0
(-2620 35);
DISPLAY 0.787234 (-2620 35);
FORCEPROP 2 LAST CDS_LIB pure_quanta
J 0
(-2625 125);
PAINT MONO (-2625 125);
DISPLAY INVISIBLE (-2625 125);
FORCEPROP 1 LAST PATH I2
J 0
(-2575 300);
DISPLAY 0.978723 (-2575 300);
PAINT WHITE (-2575 300);
DISPLAY INVISIBLE (-2575 300);
FORCEPROP 1 LAST $LOCATION R80
J 0
(-2575 350);
DISPLAY 1.021277 (-2575 350);
DISPLAY INVISIBLE (-2575 350);
FORCEPROP 2 LAST CDS_LOCATION R80
J 0
(-2575 350);
DISPLAY 1.021277 (-2575 350);
DISPLAY INVISIBLE (-2575 350);
FORCEPROP 2 LAST $SEC 1
J 0
(-2575 350);
DISPLAY 0.680851 (-2575 350);
PAINT MONO (-2575 350);
DISPLAY INVISIBLE (-2575 350);
FORCEPROP 2 LAST CDS_SEC 1
J 0
(-2575 350);
DISPLAY 1.021277 (-2575 350);
DISPLAY INVISIBLE (-2575 350);
FORCEADD OFFPAGE..1
(-3775 3125);
FORCEPROP 2 LAST $XR0 54 
J 0
(-3996 3125);
DISPLAY 0.638298 (-3996 3125);
PAINT MONO (-3996 3125);
FORCEPROP 2 LAST CDS_LIB standard
J 0
(-3775 3125);
PAINT MONO (-3775 3125);
DISPLAY INVISIBLE (-3775 3125);
FORCEPROP 1 LAST OFFPAGE TRUE
J 0
(-3450 3000);
DISPLAY 0.872340 (-3450 3000);
DISPLAY INVISIBLE (-3450 3000);
FORCEPROP 1 LAST COMMENT_BODY TRUE
J 0
(-3650 3025);
DISPLAY 0.872340 (-3650 3025);
PAINT GREEN (-3650 3025);
DISPLAY INVISIBLE (-3650 3025);
FORCEPROP 2 LAST PATH I20
J 0
(-3725 3200);
DISPLAY 1.021277 (-3725 3200);
DISPLAY INVISIBLE (-3725 3200);
FORCEADD OFFPAGE..1
(-3775 3325);
FORCEPROP 2 LAST $XR0 54 
J 0
(-3996 3325);
DISPLAY 0.638298 (-3996 3325);
PAINT MONO (-3996 3325);
FORCEPROP 2 LAST CDS_LIB standard
J 0
(-3775 3325);
PAINT MONO (-3775 3325);
DISPLAY INVISIBLE (-3775 3325);
FORCEPROP 1 LAST OFFPAGE TRUE
J 0
(-3450 3200);
DISPLAY 0.872340 (-3450 3200);
DISPLAY INVISIBLE (-3450 3200);
FORCEPROP 1 LAST COMMENT_BODY TRUE
J 0
(-3650 3225);
DISPLAY 0.872340 (-3650 3225);
PAINT GREEN (-3650 3225);
DISPLAY INVISIBLE (-3650 3225);
FORCEPROP 2 LAST PATH I21
J 0
(-3725 3400);
DISPLAY 1.021277 (-3725 3400);
DISPLAY INVISIBLE (-3725 3400);
FORCEADD OFFPAGE..1
(-3775 3275);
FORCEPROP 2 LAST $XR0 54 
J 0
(-3996 3275);
DISPLAY 0.638298 (-3996 3275);
PAINT MONO (-3996 3275);
FORCEPROP 2 LAST CDS_LIB standard
J 0
(-3775 3275);
PAINT MONO (-3775 3275);
DISPLAY INVISIBLE (-3775 3275);
FORCEPROP 1 LAST OFFPAGE TRUE
J 0
(-3450 3150);
DISPLAY 0.872340 (-3450 3150);
DISPLAY INVISIBLE (-3450 3150);
FORCEPROP 1 LAST COMMENT_BODY TRUE
J 0
(-3650 3175);
DISPLAY 0.872340 (-3650 3175);
PAINT GREEN (-3650 3175);
DISPLAY INVISIBLE (-3650 3175);
FORCEPROP 2 LAST PATH I22
J 0
(-3725 3350);
DISPLAY 1.021277 (-3725 3350);
DISPLAY INVISIBLE (-3725 3350);
FORCEADD OFFPAGE..1
(-3775 3425);
FORCEPROP 2 LAST $XR1 104 
J 0
(-4116 3425);
DISPLAY 0.638298 (-4116 3425);
PAINT MONO (-4116 3425);
FORCEPROP 2 LAST $XR0 54 
J 0
(-3996 3425);
DISPLAY 0.638298 (-3996 3425);
PAINT MONO (-3996 3425);
FORCEPROP 2 LAST CDS_LIB standard
J 0
(-3775 3425);
PAINT MONO (-3775 3425);
DISPLAY INVISIBLE (-3775 3425);
FORCEPROP 1 LAST OFFPAGE TRUE
J 0
(-3450 3300);
DISPLAY 0.872340 (-3450 3300);
DISPLAY INVISIBLE (-3450 3300);
FORCEPROP 1 LAST COMMENT_BODY TRUE
J 0
(-3650 3325);
DISPLAY 0.872340 (-3650 3325);
PAINT GREEN (-3650 3325);
DISPLAY INVISIBLE (-3650 3325);
FORCEPROP 2 LAST PATH I23
J 0
(-3725 3500);
DISPLAY 1.021277 (-3725 3500);
DISPLAY INVISIBLE (-3725 3500);
FORCEADD OFFPAGE..1
(-3775 3475);
FORCEPROP 2 LAST $XR1 104 
J 0
(-4116 3475);
DISPLAY 0.638298 (-4116 3475);
PAINT MONO (-4116 3475);
FORCEPROP 2 LAST $XR0 54 
J 0
(-3996 3475);
DISPLAY 0.638298 (-3996 3475);
PAINT MONO (-3996 3475);
FORCEPROP 2 LAST CDS_LIB standard
J 0
(-3775 3475);
PAINT MONO (-3775 3475);
DISPLAY INVISIBLE (-3775 3475);
FORCEPROP 1 LAST OFFPAGE TRUE
J 0
(-3450 3350);
DISPLAY 0.872340 (-3450 3350);
DISPLAY INVISIBLE (-3450 3350);
FORCEPROP 1 LAST COMMENT_BODY TRUE
J 0
(-3650 3375);
DISPLAY 0.872340 (-3650 3375);
PAINT GREEN (-3650 3375);
DISPLAY INVISIBLE (-3650 3375);
FORCEPROP 2 LAST PATH I24
J 0
(-3725 3550);
DISPLAY 1.021277 (-3725 3550);
DISPLAY INVISIBLE (-3725 3550);
FORCEADD OFFPAGE..1
(-3775 3900);
FORCEPROP 2 LAST $XR1 104 
J 0
(-4116 3900);
DISPLAY 0.638298 (-4116 3900);
PAINT MONO (-4116 3900);
FORCEPROP 2 LAST $XR0 54 
J 0
(-3996 3900);
DISPLAY 0.638298 (-3996 3900);
PAINT MONO (-3996 3900);
FORCEPROP 2 LAST CDS_LIB standard
J 0
(-3775 3900);
PAINT MONO (-3775 3900);
DISPLAY INVISIBLE (-3775 3900);
FORCEPROP 1 LAST OFFPAGE TRUE
J 0
(-3450 3775);
DISPLAY 0.872340 (-3450 3775);
DISPLAY INVISIBLE (-3450 3775);
FORCEPROP 1 LAST COMMENT_BODY TRUE
J 0
(-3650 3800);
DISPLAY 0.872340 (-3650 3800);
PAINT GREEN (-3650 3800);
DISPLAY INVISIBLE (-3650 3800);
FORCEPROP 2 LAST PATH I25
J 0
(-3725 3975);
DISPLAY 1.021277 (-3725 3975);
DISPLAY INVISIBLE (-3725 3975);
FORCEADD TAP..1
R 2
(-2850 2125);
FORCEPROP 3 LASTPIN (-2800 2125) SIG_NAME M_D_CPU1_SB_CB<1>
J 0
(-2790 2135);
DISPLAY 0.659574 (-2790 2135);
PAINT MONO (-2790 2135);
DISPLAY INVISIBLE (-2790 2135);
FORCEPROP 1 LASTPIN (-2800 2125) BN 1
J 2
(-2788 2133);
DISPLAY 0.680851 (-2788 2133);
PAINT GREEN (-2788 2133);
FORCEPROP 2 LAST CDS_LIB standard
J 0
(-2850 2125);
DISPLAY INVISIBLE (-2850 2125);
FORCEPROP 1 LAST BODY_TYPE PLUMBING
J 2
(-2850 2175);
DISPLAY 0.872340 (-2850 2175);
PAINT GREEN (-2850 2175);
DISPLAY INVISIBLE (-2850 2175);
FORCEPROP 1 LAST HDL_TAP TRUE
J 2
(-3175 2000);
DISPLAY 0.872340 (-3175 2000);
DISPLAY INVISIBLE (-3175 2000);
FORCEPROP 1 LAST PATH I26
J 2
(-2848 2125);
DISPLAY 0.872340 (-2848 2125);
PAINT GREEN (-2848 2125);
DISPLAY INVISIBLE (-2848 2125);
FORCEADD TAP..1
R 2
(-2850 2175);
FORCEPROP 3 LASTPIN (-2800 2175) SIG_NAME M_D_CPU1_SB_CB<2>
J 0
(-2790 2185);
DISPLAY 0.659574 (-2790 2185);
PAINT MONO (-2790 2185);
DISPLAY INVISIBLE (-2790 2185);
FORCEPROP 1 LASTPIN (-2800 2175) BN 2
J 2
(-2788 2183);
DISPLAY 0.680851 (-2788 2183);
PAINT GREEN (-2788 2183);
FORCEPROP 2 LAST CDS_LIB standard
J 0
(-2850 2175);
DISPLAY INVISIBLE (-2850 2175);
FORCEPROP 1 LAST BODY_TYPE PLUMBING
J 2
(-2850 2225);
DISPLAY 0.872340 (-2850 2225);
PAINT GREEN (-2850 2225);
DISPLAY INVISIBLE (-2850 2225);
FORCEPROP 1 LAST HDL_TAP TRUE
J 2
(-3175 2050);
DISPLAY 0.872340 (-3175 2050);
DISPLAY INVISIBLE (-3175 2050);
FORCEPROP 1 LAST PATH I27
J 2
(-2848 2175);
DISPLAY 0.872340 (-2848 2175);
PAINT GREEN (-2848 2175);
DISPLAY INVISIBLE (-2848 2175);
FORCEADD TAP..1
R 2
(-2850 2225);
FORCEPROP 3 LASTPIN (-2800 2225) SIG_NAME M_D_CPU1_SB_CB<3>
J 0
(-2790 2235);
DISPLAY 0.659574 (-2790 2235);
PAINT MONO (-2790 2235);
DISPLAY INVISIBLE (-2790 2235);
FORCEPROP 1 LASTPIN (-2800 2225) BN 3
J 2
(-2788 2233);
DISPLAY 0.680851 (-2788 2233);
PAINT GREEN (-2788 2233);
FORCEPROP 2 LAST CDS_LIB standard
J 0
(-2850 2225);
DISPLAY INVISIBLE (-2850 2225);
FORCEPROP 1 LAST BODY_TYPE PLUMBING
J 2
(-2850 2275);
DISPLAY 0.872340 (-2850 2275);
PAINT GREEN (-2850 2275);
DISPLAY INVISIBLE (-2850 2275);
FORCEPROP 1 LAST HDL_TAP TRUE
J 2
(-3175 2100);
DISPLAY 0.872340 (-3175 2100);
DISPLAY INVISIBLE (-3175 2100);
FORCEPROP 1 LAST PATH I28
J 2
(-2848 2225);
DISPLAY 0.872340 (-2848 2225);
PAINT GREEN (-2848 2225);
DISPLAY INVISIBLE (-2848 2225);
FORCEADD TAP..1
R 2
(-2850 2275);
FORCEPROP 3 LASTPIN (-2800 2275) SIG_NAME M_D_CPU1_SB_CB<4>
J 0
(-2790 2285);
DISPLAY 0.659574 (-2790 2285);
PAINT MONO (-2790 2285);
DISPLAY INVISIBLE (-2790 2285);
FORCEPROP 1 LASTPIN (-2800 2275) BN 4
J 2
(-2788 2283);
DISPLAY 0.680851 (-2788 2283);
PAINT GREEN (-2788 2283);
FORCEPROP 2 LAST CDS_LIB standard
J 0
(-2850 2275);
DISPLAY INVISIBLE (-2850 2275);
FORCEPROP 1 LAST BODY_TYPE PLUMBING
J 2
(-2850 2325);
DISPLAY 0.872340 (-2850 2325);
PAINT GREEN (-2850 2325);
DISPLAY INVISIBLE (-2850 2325);
FORCEPROP 1 LAST HDL_TAP TRUE
J 2
(-3175 2150);
DISPLAY 0.872340 (-3175 2150);
DISPLAY INVISIBLE (-3175 2150);
FORCEPROP 1 LAST PATH I29
J 2
(-2848 2275);
DISPLAY 0.872340 (-2848 2275);
PAINT GREEN (-2848 2275);
DISPLAY INVISIBLE (-2848 2275);
FORCEADD OFFPAGE..2
R 2
(-3775 325);
FORCEPROP 2 LAST $XR0 105 
J 0
(-4030 325);
DISPLAY 0.638298 (-4030 325);
PAINT MONO (-4030 325);
FORCEPROP 2 LAST CDS_LIB standard
J 0
(-3775 325);
PAINT MONO (-3775 325);
DISPLAY INVISIBLE (-3775 325);
FORCEPROP 1 LAST OFFPAGE TRUE
J 2
(-4100 200);
DISPLAY 0.872340 (-4100 200);
DISPLAY INVISIBLE (-4100 200);
FORCEPROP 1 LAST COMMENT_BODY TRUE
J 2
(-3730 230);
DISPLAY 0.872340 (-3730 230);
PAINT GREEN (-3730 230);
DISPLAY INVISIBLE (-3730 230);
FORCEPROP 2 LAST PATH I3
J 0
(-3725 400);
DISPLAY 1.021277 (-3725 400);
DISPLAY INVISIBLE (-3725 400);
FORCEADD TAP..1
R 2
(-2850 2325);
FORCEPROP 3 LASTPIN (-2800 2325) SIG_NAME M_D_CPU1_SB_CB<5>
J 0
(-2790 2335);
DISPLAY 0.659574 (-2790 2335);
PAINT MONO (-2790 2335);
DISPLAY INVISIBLE (-2790 2335);
FORCEPROP 1 LASTPIN (-2800 2325) BN 5
J 2
(-2788 2333);
DISPLAY 0.680851 (-2788 2333);
PAINT GREEN (-2788 2333);
FORCEPROP 2 LAST CDS_LIB standard
J 0
(-2850 2325);
DISPLAY INVISIBLE (-2850 2325);
FORCEPROP 1 LAST BODY_TYPE PLUMBING
J 2
(-2850 2375);
DISPLAY 0.872340 (-2850 2375);
PAINT GREEN (-2850 2375);
DISPLAY INVISIBLE (-2850 2375);
FORCEPROP 1 LAST HDL_TAP TRUE
J 2
(-3175 2200);
DISPLAY 0.872340 (-3175 2200);
DISPLAY INVISIBLE (-3175 2200);
FORCEPROP 1 LAST PATH I30
J 2
(-2848 2325);
DISPLAY 0.872340 (-2848 2325);
PAINT GREEN (-2848 2325);
DISPLAY INVISIBLE (-2848 2325);
FORCEADD TAP..1
R 2
(-2850 2375);
FORCEPROP 3 LASTPIN (-2800 2375) SIG_NAME M_D_CPU1_SB_CB<6>
J 0
(-2790 2385);
DISPLAY 0.659574 (-2790 2385);
PAINT MONO (-2790 2385);
DISPLAY INVISIBLE (-2790 2385);
FORCEPROP 1 LASTPIN (-2800 2375) BN 6
J 2
(-2788 2383);
DISPLAY 0.680851 (-2788 2383);
PAINT GREEN (-2788 2383);
FORCEPROP 2 LAST CDS_LIB standard
J 0
(-2850 2375);
DISPLAY INVISIBLE (-2850 2375);
FORCEPROP 1 LAST BODY_TYPE PLUMBING
J 2
(-2850 2425);
DISPLAY 0.872340 (-2850 2425);
PAINT GREEN (-2850 2425);
DISPLAY INVISIBLE (-2850 2425);
FORCEPROP 1 LAST HDL_TAP TRUE
J 2
(-3175 2250);
DISPLAY 0.872340 (-3175 2250);
DISPLAY INVISIBLE (-3175 2250);
FORCEPROP 1 LAST PATH I31
J 2
(-2848 2375);
DISPLAY 0.872340 (-2848 2375);
PAINT GREEN (-2848 2375);
DISPLAY INVISIBLE (-2848 2375);
FORCEADD TAP..1
R 2
(-2850 2425);
FORCEPROP 3 LASTPIN (-2800 2425) SIG_NAME M_D_CPU1_SB_CB<7>
J 0
(-2790 2435);
DISPLAY 0.659574 (-2790 2435);
PAINT MONO (-2790 2435);
DISPLAY INVISIBLE (-2790 2435);
FORCEPROP 1 LASTPIN (-2800 2425) BN 7
J 2
(-2788 2433);
DISPLAY 0.680851 (-2788 2433);
PAINT GREEN (-2788 2433);
FORCEPROP 2 LAST CDS_LIB standard
J 0
(-2850 2425);
DISPLAY INVISIBLE (-2850 2425);
FORCEPROP 1 LAST BODY_TYPE PLUMBING
J 2
(-2850 2475);
DISPLAY 0.872340 (-2850 2475);
PAINT GREEN (-2850 2475);
DISPLAY INVISIBLE (-2850 2475);
FORCEPROP 1 LAST HDL_TAP TRUE
J 2
(-3175 2300);
DISPLAY 0.872340 (-3175 2300);
DISPLAY INVISIBLE (-3175 2300);
FORCEPROP 1 LAST PATH I32
J 2
(-2848 2425);
DISPLAY 0.872340 (-2848 2425);
PAINT GREEN (-2848 2425);
DISPLAY INVISIBLE (-2848 2425);
FORCEADD TAP..1
R 2
(-2850 2575);
FORCEPROP 3 LASTPIN (-2800 2575) SIG_NAME M_D_CPU1_SA_CB<1>
J 0
(-2790 2585);
DISPLAY 0.659574 (-2790 2585);
PAINT MONO (-2790 2585);
DISPLAY INVISIBLE (-2790 2585);
FORCEPROP 1 LASTPIN (-2800 2575) BN 1
J 2
(-2788 2583);
DISPLAY 0.680851 (-2788 2583);
PAINT GREEN (-2788 2583);
FORCEPROP 2 LAST CDS_LIB standard
J 0
(-2850 2575);
DISPLAY INVISIBLE (-2850 2575);
FORCEPROP 1 LAST BODY_TYPE PLUMBING
J 2
(-2850 2625);
DISPLAY 0.872340 (-2850 2625);
PAINT GREEN (-2850 2625);
DISPLAY INVISIBLE (-2850 2625);
FORCEPROP 1 LAST HDL_TAP TRUE
J 2
(-3175 2450);
DISPLAY 0.872340 (-3175 2450);
DISPLAY INVISIBLE (-3175 2450);
FORCEPROP 1 LAST PATH I33
J 2
(-2848 2575);
DISPLAY 0.872340 (-2848 2575);
PAINT GREEN (-2848 2575);
DISPLAY INVISIBLE (-2848 2575);
FORCEADD TAP..1
R 2
(-2850 2525);
FORCEPROP 3 LASTPIN (-2800 2525) SIG_NAME M_D_CPU1_SA_CB<0>
J 0
(-2790 2535);
DISPLAY 0.659574 (-2790 2535);
PAINT MONO (-2790 2535);
DISPLAY INVISIBLE (-2790 2535);
FORCEPROP 1 LASTPIN (-2800 2525) BN 0
J 2
(-2788 2533);
DISPLAY 0.680851 (-2788 2533);
PAINT GREEN (-2788 2533);
FORCEPROP 2 LAST CDS_LIB standard
J 0
(-2850 2525);
PAINT MONO (-2850 2525);
DISPLAY INVISIBLE (-2850 2525);
FORCEPROP 1 LAST BODY_TYPE PLUMBING
J 2
(-2850 2575);
DISPLAY 0.872340 (-2850 2575);
PAINT GREEN (-2850 2575);
DISPLAY INVISIBLE (-2850 2575);
FORCEPROP 1 LAST HDL_TAP TRUE
J 2
(-3175 2400);
DISPLAY 0.872340 (-3175 2400);
DISPLAY INVISIBLE (-3175 2400);
FORCEPROP 1 LAST PATH I34
J 2
(-2848 2525);
DISPLAY 0.872340 (-2848 2525);
PAINT GREEN (-2848 2525);
DISPLAY INVISIBLE (-2848 2525);
FORCEADD TAP..1
R 2
(-2850 2625);
FORCEPROP 3 LASTPIN (-2800 2625) SIG_NAME M_D_CPU1_SA_CB<2>
J 0
(-2790 2635);
DISPLAY 0.659574 (-2790 2635);
PAINT MONO (-2790 2635);
DISPLAY INVISIBLE (-2790 2635);
FORCEPROP 1 LASTPIN (-2800 2625) BN 2
J 2
(-2788 2633);
DISPLAY 0.680851 (-2788 2633);
PAINT GREEN (-2788 2633);
FORCEPROP 2 LAST CDS_LIB standard
J 0
(-2850 2625);
DISPLAY INVISIBLE (-2850 2625);
FORCEPROP 1 LAST BODY_TYPE PLUMBING
J 2
(-2850 2675);
DISPLAY 0.872340 (-2850 2675);
PAINT GREEN (-2850 2675);
DISPLAY INVISIBLE (-2850 2675);
FORCEPROP 1 LAST HDL_TAP TRUE
J 2
(-3175 2500);
DISPLAY 0.872340 (-3175 2500);
DISPLAY INVISIBLE (-3175 2500);
FORCEPROP 1 LAST PATH I35
J 2
(-2848 2625);
DISPLAY 0.872340 (-2848 2625);
PAINT GREEN (-2848 2625);
DISPLAY INVISIBLE (-2848 2625);
FORCEADD TAP..1
R 2
(-2850 2675);
FORCEPROP 3 LASTPIN (-2800 2675) SIG_NAME M_D_CPU1_SA_CB<3>
J 0
(-2790 2685);
DISPLAY 0.659574 (-2790 2685);
PAINT MONO (-2790 2685);
DISPLAY INVISIBLE (-2790 2685);
FORCEPROP 1 LASTPIN (-2800 2675) BN 3
J 2
(-2788 2683);
DISPLAY 0.680851 (-2788 2683);
PAINT GREEN (-2788 2683);
FORCEPROP 2 LAST CDS_LIB standard
J 0
(-2850 2675);
DISPLAY INVISIBLE (-2850 2675);
FORCEPROP 1 LAST BODY_TYPE PLUMBING
J 2
(-2850 2725);
DISPLAY 0.872340 (-2850 2725);
PAINT GREEN (-2850 2725);
DISPLAY INVISIBLE (-2850 2725);
FORCEPROP 1 LAST HDL_TAP TRUE
J 2
(-3175 2550);
DISPLAY 0.872340 (-3175 2550);
DISPLAY INVISIBLE (-3175 2550);
FORCEPROP 1 LAST PATH I36
J 2
(-2848 2675);
DISPLAY 0.872340 (-2848 2675);
PAINT GREEN (-2848 2675);
DISPLAY INVISIBLE (-2848 2675);
FORCEADD TAP..1
R 2
(-2850 2725);
FORCEPROP 3 LASTPIN (-2800 2725) SIG_NAME M_D_CPU1_SA_CB<4>
J 0
(-2790 2735);
DISPLAY 0.659574 (-2790 2735);
PAINT MONO (-2790 2735);
DISPLAY INVISIBLE (-2790 2735);
FORCEPROP 1 LASTPIN (-2800 2725) BN 4
J 2
(-2788 2733);
DISPLAY 0.680851 (-2788 2733);
PAINT GREEN (-2788 2733);
FORCEPROP 2 LAST CDS_LIB standard
J 0
(-2850 2725);
DISPLAY INVISIBLE (-2850 2725);
FORCEPROP 1 LAST BODY_TYPE PLUMBING
J 2
(-2850 2775);
DISPLAY 0.872340 (-2850 2775);
PAINT GREEN (-2850 2775);
DISPLAY INVISIBLE (-2850 2775);
FORCEPROP 1 LAST HDL_TAP TRUE
J 2
(-3175 2600);
DISPLAY 0.872340 (-3175 2600);
DISPLAY INVISIBLE (-3175 2600);
FORCEPROP 1 LAST PATH I37
J 2
(-2848 2725);
DISPLAY 0.872340 (-2848 2725);
PAINT GREEN (-2848 2725);
DISPLAY INVISIBLE (-2848 2725);
FORCEADD TAP..1
R 2
(-2850 2825);
FORCEPROP 3 LASTPIN (-2800 2825) SIG_NAME M_D_CPU1_SA_CB<6>
J 0
(-2790 2835);
DISPLAY 0.659574 (-2790 2835);
PAINT MONO (-2790 2835);
DISPLAY INVISIBLE (-2790 2835);
FORCEPROP 1 LASTPIN (-2800 2825) BN 6
J 2
(-2788 2833);
DISPLAY 0.680851 (-2788 2833);
PAINT GREEN (-2788 2833);
FORCEPROP 2 LAST CDS_LIB standard
J 0
(-2850 2825);
DISPLAY INVISIBLE (-2850 2825);
FORCEPROP 1 LAST BODY_TYPE PLUMBING
J 2
(-2850 2875);
DISPLAY 0.872340 (-2850 2875);
PAINT GREEN (-2850 2875);
DISPLAY INVISIBLE (-2850 2875);
FORCEPROP 1 LAST HDL_TAP TRUE
J 2
(-3175 2700);
DISPLAY 0.872340 (-3175 2700);
DISPLAY INVISIBLE (-3175 2700);
FORCEPROP 1 LAST PATH I38
J 2
(-2848 2825);
DISPLAY 0.872340 (-2848 2825);
PAINT GREEN (-2848 2825);
DISPLAY INVISIBLE (-2848 2825);
FORCEADD TAP..1
R 2
(-2850 2775);
FORCEPROP 3 LASTPIN (-2800 2775) SIG_NAME M_D_CPU1_SA_CB<5>
J 0
(-2790 2785);
DISPLAY 0.659574 (-2790 2785);
PAINT MONO (-2790 2785);
DISPLAY INVISIBLE (-2790 2785);
FORCEPROP 1 LASTPIN (-2800 2775) BN 5
J 2
(-2788 2783);
DISPLAY 0.680851 (-2788 2783);
PAINT GREEN (-2788 2783);
FORCEPROP 2 LAST CDS_LIB standard
J 0
(-2850 2775);
DISPLAY INVISIBLE (-2850 2775);
FORCEPROP 1 LAST BODY_TYPE PLUMBING
J 2
(-2850 2825);
DISPLAY 0.872340 (-2850 2825);
PAINT GREEN (-2850 2825);
DISPLAY INVISIBLE (-2850 2825);
FORCEPROP 1 LAST HDL_TAP TRUE
J 2
(-3175 2650);
DISPLAY 0.872340 (-3175 2650);
DISPLAY INVISIBLE (-3175 2650);
FORCEPROP 1 LAST PATH I39
J 2
(-2848 2775);
DISPLAY 0.872340 (-2848 2775);
PAINT GREEN (-2848 2775);
DISPLAY INVISIBLE (-2848 2775);
FORCEADD OFFPAGE..2
R 2
(-3775 875);
FORCEPROP 2 LAST $XR0 54 
J 0
(-3999 875);
DISPLAY 0.638298 (-3999 875);
PAINT MONO (-3999 875);
FORCEPROP 2 LAST CDS_LIB standard
J 0
(-3775 875);
PAINT MONO (-3775 875);
DISPLAY INVISIBLE (-3775 875);
FORCEPROP 1 LAST OFFPAGE TRUE
J 2
(-4100 750);
DISPLAY 0.872340 (-4100 750);
DISPLAY INVISIBLE (-4100 750);
FORCEPROP 1 LAST COMMENT_BODY TRUE
J 2
(-3730 780);
DISPLAY 0.872340 (-3730 780);
PAINT GREEN (-3730 780);
DISPLAY INVISIBLE (-3730 780);
FORCEPROP 2 LAST PATH I4
J 0
(-3725 950);
DISPLAY 1.021277 (-3725 950);
DISPLAY INVISIBLE (-3725 950);
FORCEADD TAP..1
R 2
(-2850 2875);
FORCEPROP 3 LASTPIN (-2800 2875) SIG_NAME M_D_CPU1_SA_CB<7>
J 0
(-2790 2885);
DISPLAY 0.659574 (-2790 2885);
PAINT MONO (-2790 2885);
DISPLAY INVISIBLE (-2790 2885);
FORCEPROP 1 LASTPIN (-2800 2875) BN 7
J 2
(-2788 2883);
DISPLAY 0.680851 (-2788 2883);
PAINT GREEN (-2788 2883);
FORCEPROP 2 LAST CDS_LIB standard
J 0
(-2850 2875);
DISPLAY INVISIBLE (-2850 2875);
FORCEPROP 1 LAST BODY_TYPE PLUMBING
J 2
(-2850 2925);
DISPLAY 0.872340 (-2850 2925);
PAINT GREEN (-2850 2925);
DISPLAY INVISIBLE (-2850 2925);
FORCEPROP 1 LAST HDL_TAP TRUE
J 2
(-3175 2750);
DISPLAY 0.872340 (-3175 2750);
DISPLAY INVISIBLE (-3175 2750);
FORCEPROP 1 LAST PATH I40
J 2
(-2848 2875);
DISPLAY 0.872340 (-2848 2875);
PAINT GREEN (-2848 2875);
DISPLAY INVISIBLE (-2848 2875);
FORCEADD TAP..1
R 2
(-2850 3575);
FORCEPROP 3 LASTPIN (-2800 3575) SIG_NAME M_D_CPU1_SB_CA<0>
J 0
(-2790 3585);
DISPLAY 0.659574 (-2790 3585);
PAINT MONO (-2790 3585);
DISPLAY INVISIBLE (-2790 3585);
FORCEPROP 1 LASTPIN (-2800 3575) BN 0
J 2
(-2788 3583);
DISPLAY 0.680851 (-2788 3583);
PAINT GREEN (-2788 3583);
FORCEPROP 2 LAST CDS_LIB standard
J 0
(-2850 3575);
DISPLAY INVISIBLE (-2850 3575);
FORCEPROP 1 LAST BODY_TYPE PLUMBING
J 2
(-2850 3625);
DISPLAY 0.872340 (-2850 3625);
PAINT GREEN (-2850 3625);
DISPLAY INVISIBLE (-2850 3625);
FORCEPROP 1 LAST HDL_TAP TRUE
J 2
(-3175 3450);
DISPLAY 0.872340 (-3175 3450);
DISPLAY INVISIBLE (-3175 3450);
FORCEPROP 1 LAST PATH I41
J 2
(-2848 3575);
DISPLAY 0.872340 (-2848 3575);
PAINT GREEN (-2848 3575);
DISPLAY INVISIBLE (-2848 3575);
FORCEADD TAP..1
R 2
(-2850 3625);
FORCEPROP 3 LASTPIN (-2800 3625) SIG_NAME M_D_CPU1_SB_CA<1>
J 0
(-2790 3635);
DISPLAY 0.659574 (-2790 3635);
PAINT MONO (-2790 3635);
DISPLAY INVISIBLE (-2790 3635);
FORCEPROP 1 LASTPIN (-2800 3625) BN 1
J 2
(-2788 3633);
DISPLAY 0.680851 (-2788 3633);
PAINT GREEN (-2788 3633);
FORCEPROP 2 LAST CDS_LIB standard
J 0
(-2850 3625);
DISPLAY INVISIBLE (-2850 3625);
FORCEPROP 1 LAST BODY_TYPE PLUMBING
J 2
(-2850 3675);
DISPLAY 0.872340 (-2850 3675);
PAINT GREEN (-2850 3675);
DISPLAY INVISIBLE (-2850 3675);
FORCEPROP 1 LAST HDL_TAP TRUE
J 2
(-3175 3500);
DISPLAY 0.872340 (-3175 3500);
DISPLAY INVISIBLE (-3175 3500);
FORCEPROP 1 LAST PATH I42
J 2
(-2848 3625);
DISPLAY 0.872340 (-2848 3625);
PAINT GREEN (-2848 3625);
DISPLAY INVISIBLE (-2848 3625);
FORCEADD TAP..1
R 2
(-2850 3675);
FORCEPROP 3 LASTPIN (-2800 3675) SIG_NAME M_D_CPU1_SB_CA<2>
J 0
(-2790 3685);
DISPLAY 0.659574 (-2790 3685);
PAINT MONO (-2790 3685);
DISPLAY INVISIBLE (-2790 3685);
FORCEPROP 1 LASTPIN (-2800 3675) BN 2
J 2
(-2788 3683);
DISPLAY 0.680851 (-2788 3683);
PAINT GREEN (-2788 3683);
FORCEPROP 2 LAST CDS_LIB standard
J 0
(-2850 3675);
DISPLAY INVISIBLE (-2850 3675);
FORCEPROP 1 LAST BODY_TYPE PLUMBING
J 2
(-2850 3725);
DISPLAY 0.872340 (-2850 3725);
PAINT GREEN (-2850 3725);
DISPLAY INVISIBLE (-2850 3725);
FORCEPROP 1 LAST HDL_TAP TRUE
J 2
(-3175 3550);
DISPLAY 0.872340 (-3175 3550);
DISPLAY INVISIBLE (-3175 3550);
FORCEPROP 1 LAST PATH I43
J 2
(-2848 3675);
DISPLAY 0.872340 (-2848 3675);
PAINT GREEN (-2848 3675);
DISPLAY INVISIBLE (-2848 3675);
FORCEADD TAP..1
R 2
(-2850 3725);
FORCEPROP 3 LASTPIN (-2800 3725) SIG_NAME M_D_CPU1_SB_CA<3>
J 0
(-2790 3735);
DISPLAY 0.659574 (-2790 3735);
PAINT MONO (-2790 3735);
DISPLAY INVISIBLE (-2790 3735);
FORCEPROP 1 LASTPIN (-2800 3725) BN 3
J 2
(-2788 3733);
DISPLAY 0.680851 (-2788 3733);
PAINT GREEN (-2788 3733);
FORCEPROP 2 LAST CDS_LIB standard
J 0
(-2850 3725);
DISPLAY INVISIBLE (-2850 3725);
FORCEPROP 1 LAST BODY_TYPE PLUMBING
J 2
(-2850 3775);
DISPLAY 0.872340 (-2850 3775);
PAINT GREEN (-2850 3775);
DISPLAY INVISIBLE (-2850 3775);
FORCEPROP 1 LAST HDL_TAP TRUE
J 2
(-3175 3600);
DISPLAY 0.872340 (-3175 3600);
DISPLAY INVISIBLE (-3175 3600);
FORCEPROP 1 LAST PATH I44
J 2
(-2848 3725);
DISPLAY 0.872340 (-2848 3725);
PAINT GREEN (-2848 3725);
DISPLAY INVISIBLE (-2848 3725);
FORCEADD TAP..1
R 2
(-2850 3775);
FORCEPROP 3 LASTPIN (-2800 3775) SIG_NAME M_D_CPU1_SB_CA<4>
J 0
(-2790 3785);
DISPLAY 0.659574 (-2790 3785);
PAINT MONO (-2790 3785);
DISPLAY INVISIBLE (-2790 3785);
FORCEPROP 1 LASTPIN (-2800 3775) BN 4
J 2
(-2788 3783);
DISPLAY 0.680851 (-2788 3783);
PAINT GREEN (-2788 3783);
FORCEPROP 2 LAST CDS_LIB standard
J 0
(-2850 3775);
DISPLAY INVISIBLE (-2850 3775);
FORCEPROP 1 LAST BODY_TYPE PLUMBING
J 2
(-2850 3825);
DISPLAY 0.872340 (-2850 3825);
PAINT GREEN (-2850 3825);
DISPLAY INVISIBLE (-2850 3825);
FORCEPROP 1 LAST HDL_TAP TRUE
J 2
(-3175 3650);
DISPLAY 0.872340 (-3175 3650);
DISPLAY INVISIBLE (-3175 3650);
FORCEPROP 1 LAST PATH I45
J 2
(-2848 3775);
DISPLAY 0.872340 (-2848 3775);
PAINT GREEN (-2848 3775);
DISPLAY INVISIBLE (-2848 3775);
FORCEADD TAP..1
R 2
(-2850 3875);
FORCEPROP 3 LASTPIN (-2800 3875) SIG_NAME M_D_CPU1_SB_CA<6>
J 0
(-2790 3885);
DISPLAY 0.659574 (-2790 3885);
PAINT MONO (-2790 3885);
DISPLAY INVISIBLE (-2790 3885);
FORCEPROP 1 LASTPIN (-2800 3875) BN 6
J 2
(-2788 3883);
DISPLAY 0.680851 (-2788 3883);
PAINT GREEN (-2788 3883);
FORCEPROP 2 LAST CDS_LIB standard
J 0
(-2850 3875);
DISPLAY INVISIBLE (-2850 3875);
FORCEPROP 1 LAST BODY_TYPE PLUMBING
J 2
(-2850 3925);
DISPLAY 0.872340 (-2850 3925);
PAINT GREEN (-2850 3925);
DISPLAY INVISIBLE (-2850 3925);
FORCEPROP 1 LAST HDL_TAP TRUE
J 2
(-3175 3750);
DISPLAY 0.872340 (-3175 3750);
DISPLAY INVISIBLE (-3175 3750);
FORCEPROP 1 LAST PATH I46
J 2
(-2848 3875);
DISPLAY 0.872340 (-2848 3875);
PAINT GREEN (-2848 3875);
DISPLAY INVISIBLE (-2848 3875);
FORCEADD TAP..1
R 2
(-2850 3825);
FORCEPROP 3 LASTPIN (-2800 3825) SIG_NAME M_D_CPU1_SB_CA<5>
J 0
(-2790 3835);
DISPLAY 0.659574 (-2790 3835);
PAINT MONO (-2790 3835);
DISPLAY INVISIBLE (-2790 3835);
FORCEPROP 1 LASTPIN (-2800 3825) BN 5
J 2
(-2788 3833);
DISPLAY 0.680851 (-2788 3833);
PAINT GREEN (-2788 3833);
FORCEPROP 2 LAST CDS_LIB standard
J 0
(-2850 3825);
DISPLAY INVISIBLE (-2850 3825);
FORCEPROP 1 LAST BODY_TYPE PLUMBING
J 2
(-2850 3875);
DISPLAY 0.872340 (-2850 3875);
PAINT GREEN (-2850 3875);
DISPLAY INVISIBLE (-2850 3875);
FORCEPROP 1 LAST HDL_TAP TRUE
J 2
(-3175 3700);
DISPLAY 0.872340 (-3175 3700);
DISPLAY INVISIBLE (-3175 3700);
FORCEPROP 1 LAST PATH I47
J 2
(-2848 3825);
DISPLAY 0.872340 (-2848 3825);
PAINT GREEN (-2848 3825);
DISPLAY INVISIBLE (-2848 3825);
FORCEADD TAP..1
R 2
(-2850 3975);
FORCEPROP 3 LASTPIN (-2800 3975) SIG_NAME M_D_CPU1_SA_CA<0>
J 0
(-2790 3985);
DISPLAY 0.659574 (-2790 3985);
PAINT MONO (-2790 3985);
DISPLAY INVISIBLE (-2790 3985);
FORCEPROP 1 LASTPIN (-2800 3975) BN 0
J 2
(-2788 3983);
DISPLAY 0.680851 (-2788 3983);
PAINT GREEN (-2788 3983);
FORCEPROP 2 LAST CDS_LIB standard
J 0
(-2850 3975);
DISPLAY INVISIBLE (-2850 3975);
FORCEPROP 1 LAST BODY_TYPE PLUMBING
J 2
(-2850 4025);
DISPLAY 0.872340 (-2850 4025);
PAINT GREEN (-2850 4025);
DISPLAY INVISIBLE (-2850 4025);
FORCEPROP 1 LAST HDL_TAP TRUE
J 2
(-3175 3850);
DISPLAY 0.872340 (-3175 3850);
DISPLAY INVISIBLE (-3175 3850);
FORCEPROP 1 LAST PATH I48
J 2
(-2848 3975);
DISPLAY 0.872340 (-2848 3975);
PAINT GREEN (-2848 3975);
DISPLAY INVISIBLE (-2848 3975);
FORCEADD TAP..1
R 2
(-2850 4025);
FORCEPROP 3 LASTPIN (-2800 4025) SIG_NAME M_D_CPU1_SA_CA<1>
J 0
(-2790 4035);
DISPLAY 0.659574 (-2790 4035);
PAINT MONO (-2790 4035);
DISPLAY INVISIBLE (-2790 4035);
FORCEPROP 1 LASTPIN (-2800 4025) BN 1
J 2
(-2788 4033);
DISPLAY 0.680851 (-2788 4033);
PAINT GREEN (-2788 4033);
FORCEPROP 2 LAST CDS_LIB standard
J 0
(-2850 4025);
DISPLAY INVISIBLE (-2850 4025);
FORCEPROP 1 LAST BODY_TYPE PLUMBING
J 2
(-2850 4075);
DISPLAY 0.872340 (-2850 4075);
PAINT GREEN (-2850 4075);
DISPLAY INVISIBLE (-2850 4075);
FORCEPROP 1 LAST HDL_TAP TRUE
J 2
(-3175 3900);
DISPLAY 0.872340 (-3175 3900);
DISPLAY INVISIBLE (-3175 3900);
FORCEPROP 1 LAST PATH I49
J 2
(-2848 4025);
DISPLAY 0.872340 (-2848 4025);
PAINT GREEN (-2848 4025);
DISPLAY INVISIBLE (-2848 4025);
FORCEADD OFFPAGE..2
R 2
(-3775 825);
FORCEPROP 2 LAST $XR0 54 
J 0
(-3999 825);
DISPLAY 0.638298 (-3999 825);
PAINT MONO (-3999 825);
FORCEPROP 2 LAST CDS_LIB standard
J 0
(-3775 825);
PAINT MONO (-3775 825);
DISPLAY INVISIBLE (-3775 825);
FORCEPROP 1 LAST OFFPAGE TRUE
J 2
(-4100 700);
DISPLAY 0.872340 (-4100 700);
DISPLAY INVISIBLE (-4100 700);
FORCEPROP 1 LAST COMMENT_BODY TRUE
J 2
(-3730 730);
DISPLAY 0.872340 (-3730 730);
PAINT GREEN (-3730 730);
DISPLAY INVISIBLE (-3730 730);
FORCEPROP 2 LAST PATH I5
J 0
(-3725 900);
DISPLAY 1.021277 (-3725 900);
DISPLAY INVISIBLE (-3725 900);
FORCEADD TAP..1
R 2
(-2850 4075);
FORCEPROP 3 LASTPIN (-2800 4075) SIG_NAME M_D_CPU1_SA_CA<2>
J 0
(-2790 4085);
DISPLAY 0.659574 (-2790 4085);
PAINT MONO (-2790 4085);
DISPLAY INVISIBLE (-2790 4085);
FORCEPROP 1 LASTPIN (-2800 4075) BN 2
J 2
(-2788 4083);
DISPLAY 0.680851 (-2788 4083);
PAINT GREEN (-2788 4083);
FORCEPROP 2 LAST CDS_LIB standard
J 0
(-2850 4075);
DISPLAY INVISIBLE (-2850 4075);
FORCEPROP 1 LAST BODY_TYPE PLUMBING
J 2
(-2850 4125);
DISPLAY 0.872340 (-2850 4125);
PAINT GREEN (-2850 4125);
DISPLAY INVISIBLE (-2850 4125);
FORCEPROP 1 LAST HDL_TAP TRUE
J 2
(-3175 3950);
DISPLAY 0.872340 (-3175 3950);
DISPLAY INVISIBLE (-3175 3950);
FORCEPROP 1 LAST PATH I50
J 2
(-2848 4075);
DISPLAY 0.872340 (-2848 4075);
PAINT GREEN (-2848 4075);
DISPLAY INVISIBLE (-2848 4075);
FORCEADD TAP..1
R 2
(-2850 4125);
FORCEPROP 3 LASTPIN (-2800 4125) SIG_NAME M_D_CPU1_SA_CA<3>
J 0
(-2790 4135);
DISPLAY 0.659574 (-2790 4135);
PAINT MONO (-2790 4135);
DISPLAY INVISIBLE (-2790 4135);
FORCEPROP 1 LASTPIN (-2800 4125) BN 3
J 2
(-2788 4133);
DISPLAY 0.680851 (-2788 4133);
PAINT GREEN (-2788 4133);
FORCEPROP 2 LAST CDS_LIB standard
J 0
(-2850 4125);
DISPLAY INVISIBLE (-2850 4125);
FORCEPROP 1 LAST BODY_TYPE PLUMBING
J 2
(-2850 4175);
DISPLAY 0.872340 (-2850 4175);
PAINT GREEN (-2850 4175);
DISPLAY INVISIBLE (-2850 4175);
FORCEPROP 1 LAST HDL_TAP TRUE
J 2
(-3175 4000);
DISPLAY 0.872340 (-3175 4000);
DISPLAY INVISIBLE (-3175 4000);
FORCEPROP 1 LAST PATH I51
J 2
(-2848 4125);
DISPLAY 0.872340 (-2848 4125);
PAINT GREEN (-2848 4125);
DISPLAY INVISIBLE (-2848 4125);
FORCEADD TAP..1
(-1200 1075);
FORCEPROP 3 LASTPIN (-1250 1075) SIG_NAME M_D_CPU1_SB_DQ<0>
J 0
(-1240 1085);
DISPLAY 0.659574 (-1240 1085);
PAINT MONO (-1240 1085);
DISPLAY INVISIBLE (-1240 1085);
FORCEPROP 1 LASTPIN (-1250 1075) BN 0
J 0
(-1262 1083);
DISPLAY 0.680851 (-1262 1083);
PAINT GREEN (-1262 1083);
FORCEPROP 2 LAST CDS_LIB standard
J 0
(-1200 1075);
PAINT MONO (-1200 1075);
DISPLAY INVISIBLE (-1200 1075);
FORCEPROP 1 LAST BODY_TYPE PLUMBING
J 0
(-1200 1125);
DISPLAY 0.872340 (-1200 1125);
PAINT GREEN (-1200 1125);
DISPLAY INVISIBLE (-1200 1125);
FORCEPROP 1 LAST HDL_TAP TRUE
J 0
(-875 950);
DISPLAY 0.872340 (-875 950);
DISPLAY INVISIBLE (-875 950);
FORCEPROP 1 LAST PATH I52
J 0
(-1202 1075);
DISPLAY 0.872340 (-1202 1075);
PAINT GREEN (-1202 1075);
DISPLAY INVISIBLE (-1202 1075);
FORCEADD TAP..1
(-1200 1125);
FORCEPROP 3 LASTPIN (-1250 1125) SIG_NAME M_D_CPU1_SB_DQ<1>
J 0
(-1240 1135);
DISPLAY 0.659574 (-1240 1135);
PAINT MONO (-1240 1135);
DISPLAY INVISIBLE (-1240 1135);
FORCEPROP 1 LASTPIN (-1250 1125) BN 1
J 0
(-1262 1133);
DISPLAY 0.680851 (-1262 1133);
PAINT GREEN (-1262 1133);
FORCEPROP 2 LAST CDS_LIB standard
J 0
(-1200 1125);
PAINT MONO (-1200 1125);
DISPLAY INVISIBLE (-1200 1125);
FORCEPROP 1 LAST BODY_TYPE PLUMBING
J 0
(-1200 1175);
DISPLAY 0.872340 (-1200 1175);
PAINT GREEN (-1200 1175);
DISPLAY INVISIBLE (-1200 1175);
FORCEPROP 1 LAST HDL_TAP TRUE
J 0
(-875 1000);
DISPLAY 0.872340 (-875 1000);
DISPLAY INVISIBLE (-875 1000);
FORCEPROP 1 LAST PATH I53
J 0
(-1202 1125);
DISPLAY 0.872340 (-1202 1125);
PAINT GREEN (-1202 1125);
DISPLAY INVISIBLE (-1202 1125);
FORCEADD TAP..1
(-1200 1225);
FORCEPROP 3 LASTPIN (-1250 1225) SIG_NAME M_D_CPU1_SB_DQ<3>
J 0
(-1240 1235);
DISPLAY 0.659574 (-1240 1235);
PAINT MONO (-1240 1235);
DISPLAY INVISIBLE (-1240 1235);
FORCEPROP 1 LASTPIN (-1250 1225) BN 3
J 0
(-1262 1233);
DISPLAY 0.680851 (-1262 1233);
PAINT GREEN (-1262 1233);
FORCEPROP 2 LAST CDS_LIB standard
J 0
(-1200 1225);
PAINT MONO (-1200 1225);
DISPLAY INVISIBLE (-1200 1225);
FORCEPROP 1 LAST BODY_TYPE PLUMBING
J 0
(-1200 1275);
DISPLAY 0.872340 (-1200 1275);
PAINT GREEN (-1200 1275);
DISPLAY INVISIBLE (-1200 1275);
FORCEPROP 1 LAST HDL_TAP TRUE
J 0
(-875 1100);
DISPLAY 0.872340 (-875 1100);
DISPLAY INVISIBLE (-875 1100);
FORCEPROP 1 LAST PATH I54
J 0
(-1202 1225);
DISPLAY 0.872340 (-1202 1225);
PAINT GREEN (-1202 1225);
DISPLAY INVISIBLE (-1202 1225);
FORCEADD TAP..1
(-1200 1175);
FORCEPROP 3 LASTPIN (-1250 1175) SIG_NAME M_D_CPU1_SB_DQ<2>
J 0
(-1240 1185);
DISPLAY 0.659574 (-1240 1185);
PAINT MONO (-1240 1185);
DISPLAY INVISIBLE (-1240 1185);
FORCEPROP 1 LASTPIN (-1250 1175) BN 2
J 0
(-1262 1183);
DISPLAY 0.680851 (-1262 1183);
PAINT GREEN (-1262 1183);
FORCEPROP 2 LAST CDS_LIB standard
J 0
(-1200 1175);
PAINT MONO (-1200 1175);
DISPLAY INVISIBLE (-1200 1175);
FORCEPROP 1 LAST BODY_TYPE PLUMBING
J 0
(-1200 1225);
DISPLAY 0.872340 (-1200 1225);
PAINT GREEN (-1200 1225);
DISPLAY INVISIBLE (-1200 1225);
FORCEPROP 1 LAST HDL_TAP TRUE
J 0
(-875 1050);
DISPLAY 0.872340 (-875 1050);
DISPLAY INVISIBLE (-875 1050);
FORCEPROP 1 LAST PATH I55
J 0
(-1202 1175);
DISPLAY 0.872340 (-1202 1175);
PAINT GREEN (-1202 1175);
DISPLAY INVISIBLE (-1202 1175);
FORCEADD TAP..1
(-1200 1275);
FORCEPROP 3 LASTPIN (-1250 1275) SIG_NAME M_D_CPU1_SB_DQ<4>
J 0
(-1240 1285);
DISPLAY 0.659574 (-1240 1285);
PAINT MONO (-1240 1285);
DISPLAY INVISIBLE (-1240 1285);
FORCEPROP 1 LASTPIN (-1250 1275) BN 4
J 0
(-1262 1283);
DISPLAY 0.680851 (-1262 1283);
PAINT GREEN (-1262 1283);
FORCEPROP 2 LAST CDS_LIB standard
J 0
(-1200 1275);
PAINT MONO (-1200 1275);
DISPLAY INVISIBLE (-1200 1275);
FORCEPROP 1 LAST BODY_TYPE PLUMBING
J 0
(-1200 1325);
DISPLAY 0.872340 (-1200 1325);
PAINT GREEN (-1200 1325);
DISPLAY INVISIBLE (-1200 1325);
FORCEPROP 1 LAST HDL_TAP TRUE
J 0
(-875 1150);
DISPLAY 0.872340 (-875 1150);
DISPLAY INVISIBLE (-875 1150);
FORCEPROP 1 LAST PATH I56
J 0
(-1202 1275);
DISPLAY 0.872340 (-1202 1275);
PAINT GREEN (-1202 1275);
DISPLAY INVISIBLE (-1202 1275);
FORCEADD TAP..1
(-1200 1325);
FORCEPROP 3 LASTPIN (-1250 1325) SIG_NAME M_D_CPU1_SB_DQ<5>
J 0
(-1240 1335);
DISPLAY 0.659574 (-1240 1335);
PAINT MONO (-1240 1335);
DISPLAY INVISIBLE (-1240 1335);
FORCEPROP 1 LASTPIN (-1250 1325) BN 5
J 0
(-1262 1333);
DISPLAY 0.680851 (-1262 1333);
PAINT GREEN (-1262 1333);
FORCEPROP 2 LAST CDS_LIB standard
J 0
(-1200 1325);
PAINT MONO (-1200 1325);
DISPLAY INVISIBLE (-1200 1325);
FORCEPROP 1 LAST BODY_TYPE PLUMBING
J 0
(-1200 1375);
DISPLAY 0.872340 (-1200 1375);
PAINT GREEN (-1200 1375);
DISPLAY INVISIBLE (-1200 1375);
FORCEPROP 1 LAST HDL_TAP TRUE
J 0
(-875 1200);
DISPLAY 0.872340 (-875 1200);
DISPLAY INVISIBLE (-875 1200);
FORCEPROP 1 LAST PATH I57
J 0
(-1202 1325);
DISPLAY 0.872340 (-1202 1325);
PAINT GREEN (-1202 1325);
DISPLAY INVISIBLE (-1202 1325);
FORCEADD TAP..1
(-1200 1375);
FORCEPROP 3 LASTPIN (-1250 1375) SIG_NAME M_D_CPU1_SB_DQ<6>
J 0
(-1240 1385);
DISPLAY 0.659574 (-1240 1385);
PAINT MONO (-1240 1385);
DISPLAY INVISIBLE (-1240 1385);
FORCEPROP 1 LASTPIN (-1250 1375) BN 6
J 0
(-1262 1383);
DISPLAY 0.680851 (-1262 1383);
PAINT GREEN (-1262 1383);
FORCEPROP 2 LAST CDS_LIB standard
J 0
(-1200 1375);
PAINT MONO (-1200 1375);
DISPLAY INVISIBLE (-1200 1375);
FORCEPROP 1 LAST BODY_TYPE PLUMBING
J 0
(-1200 1425);
DISPLAY 0.872340 (-1200 1425);
PAINT GREEN (-1200 1425);
DISPLAY INVISIBLE (-1200 1425);
FORCEPROP 1 LAST HDL_TAP TRUE
J 0
(-875 1250);
DISPLAY 0.872340 (-875 1250);
DISPLAY INVISIBLE (-875 1250);
FORCEPROP 1 LAST PATH I58
J 0
(-1202 1375);
DISPLAY 0.872340 (-1202 1375);
PAINT GREEN (-1202 1375);
DISPLAY INVISIBLE (-1202 1375);
FORCEADD TAP..1
(-1200 1475);
FORCEPROP 3 LASTPIN (-1250 1475) SIG_NAME M_D_CPU1_SB_DQ<8>
J 0
(-1240 1485);
DISPLAY 0.659574 (-1240 1485);
PAINT MONO (-1240 1485);
DISPLAY INVISIBLE (-1240 1485);
FORCEPROP 1 LASTPIN (-1250 1475) BN 8
J 0
(-1262 1483);
DISPLAY 0.680851 (-1262 1483);
PAINT GREEN (-1262 1483);
FORCEPROP 2 LAST CDS_LIB standard
J 0
(-1200 1475);
PAINT MONO (-1200 1475);
DISPLAY INVISIBLE (-1200 1475);
FORCEPROP 1 LAST BODY_TYPE PLUMBING
J 0
(-1200 1525);
DISPLAY 0.872340 (-1200 1525);
PAINT GREEN (-1200 1525);
DISPLAY INVISIBLE (-1200 1525);
FORCEPROP 1 LAST HDL_TAP TRUE
J 0
(-875 1350);
DISPLAY 0.872340 (-875 1350);
DISPLAY INVISIBLE (-875 1350);
FORCEPROP 1 LAST PATH I59
J 0
(-1202 1475);
DISPLAY 0.872340 (-1202 1475);
PAINT GREEN (-1202 1475);
DISPLAY INVISIBLE (-1202 1475);
FORCEADD OFFPAGE..3
R 2
(-3775 1425);
FORCEPROP 2 LAST $XR0 114 
J 0
(-4055 1425);
DISPLAY 0.638298 (-4055 1425);
PAINT MONO (-4055 1425);
FORCEPROP 2 LAST CDS_LIB standard
J 0
(-3775 1425);
PAINT MONO (-3775 1425);
DISPLAY INVISIBLE (-3775 1425);
FORCEPROP 1 LAST OFFPAGE TRUE
J 2
(-4100 1300);
DISPLAY 0.872340 (-4100 1300);
DISPLAY INVISIBLE (-4100 1300);
FORCEPROP 1 LAST COMMENT_BODY TRUE
J 2
(-3725 1325);
DISPLAY 0.872340 (-3725 1325);
PAINT GREEN (-3725 1325);
DISPLAY INVISIBLE (-3725 1325);
FORCEPROP 2 LAST PATH I6
J 0
(-3725 1500);
DISPLAY 1.021277 (-3725 1500);
DISPLAY INVISIBLE (-3725 1500);
FORCEADD TAP..1
(-1200 1425);
FORCEPROP 3 LASTPIN (-1250 1425) SIG_NAME M_D_CPU1_SB_DQ<7>
J 0
(-1240 1435);
DISPLAY 0.659574 (-1240 1435);
PAINT MONO (-1240 1435);
DISPLAY INVISIBLE (-1240 1435);
FORCEPROP 1 LASTPIN (-1250 1425) BN 7
J 0
(-1262 1433);
DISPLAY 0.680851 (-1262 1433);
PAINT GREEN (-1262 1433);
FORCEPROP 2 LAST CDS_LIB standard
J 0
(-1200 1425);
PAINT MONO (-1200 1425);
DISPLAY INVISIBLE (-1200 1425);
FORCEPROP 1 LAST BODY_TYPE PLUMBING
J 0
(-1200 1475);
DISPLAY 0.872340 (-1200 1475);
PAINT GREEN (-1200 1475);
DISPLAY INVISIBLE (-1200 1475);
FORCEPROP 1 LAST HDL_TAP TRUE
J 0
(-875 1300);
DISPLAY 0.872340 (-875 1300);
DISPLAY INVISIBLE (-875 1300);
FORCEPROP 1 LAST PATH I60
J 0
(-1202 1425);
DISPLAY 0.872340 (-1202 1425);
PAINT GREEN (-1202 1425);
DISPLAY INVISIBLE (-1202 1425);
FORCEADD TAP..1
(-1200 1525);
FORCEPROP 3 LASTPIN (-1250 1525) SIG_NAME M_D_CPU1_SB_DQ<9>
J 0
(-1240 1535);
DISPLAY 0.659574 (-1240 1535);
PAINT MONO (-1240 1535);
DISPLAY INVISIBLE (-1240 1535);
FORCEPROP 1 LASTPIN (-1250 1525) BN 9
J 0
(-1262 1533);
DISPLAY 0.680851 (-1262 1533);
PAINT GREEN (-1262 1533);
FORCEPROP 2 LAST CDS_LIB standard
J 0
(-1200 1525);
PAINT MONO (-1200 1525);
DISPLAY INVISIBLE (-1200 1525);
FORCEPROP 1 LAST BODY_TYPE PLUMBING
J 0
(-1200 1575);
DISPLAY 0.872340 (-1200 1575);
PAINT GREEN (-1200 1575);
DISPLAY INVISIBLE (-1200 1575);
FORCEPROP 1 LAST HDL_TAP TRUE
J 0
(-875 1400);
DISPLAY 0.872340 (-875 1400);
DISPLAY INVISIBLE (-875 1400);
FORCEPROP 1 LAST PATH I61
J 0
(-1202 1525);
DISPLAY 0.872340 (-1202 1525);
PAINT GREEN (-1202 1525);
DISPLAY INVISIBLE (-1202 1525);
FORCEADD TAP..1
(-1200 1575);
FORCEPROP 3 LASTPIN (-1250 1575) SIG_NAME M_D_CPU1_SB_DQ<10>
J 0
(-1240 1585);
DISPLAY 0.659574 (-1240 1585);
PAINT MONO (-1240 1585);
DISPLAY INVISIBLE (-1240 1585);
FORCEPROP 1 LASTPIN (-1250 1575) BN 10
J 0
(-1262 1583);
DISPLAY 0.680851 (-1262 1583);
PAINT GREEN (-1262 1583);
FORCEPROP 2 LAST CDS_LIB standard
J 0
(-1200 1575);
PAINT MONO (-1200 1575);
DISPLAY INVISIBLE (-1200 1575);
FORCEPROP 1 LAST BODY_TYPE PLUMBING
J 0
(-1200 1625);
DISPLAY 0.872340 (-1200 1625);
PAINT GREEN (-1200 1625);
DISPLAY INVISIBLE (-1200 1625);
FORCEPROP 1 LAST HDL_TAP TRUE
J 0
(-875 1450);
DISPLAY 0.872340 (-875 1450);
DISPLAY INVISIBLE (-875 1450);
FORCEPROP 1 LAST PATH I62
J 0
(-1202 1575);
DISPLAY 0.872340 (-1202 1575);
PAINT GREEN (-1202 1575);
DISPLAY INVISIBLE (-1202 1575);
FORCEADD TAP..1
(-1200 1625);
FORCEPROP 3 LASTPIN (-1250 1625) SIG_NAME M_D_CPU1_SB_DQ<11>
J 0
(-1240 1635);
DISPLAY 0.659574 (-1240 1635);
PAINT MONO (-1240 1635);
DISPLAY INVISIBLE (-1240 1635);
FORCEPROP 1 LASTPIN (-1250 1625) BN 11
J 0
(-1262 1633);
DISPLAY 0.680851 (-1262 1633);
PAINT GREEN (-1262 1633);
FORCEPROP 2 LAST CDS_LIB standard
J 0
(-1200 1625);
PAINT MONO (-1200 1625);
DISPLAY INVISIBLE (-1200 1625);
FORCEPROP 1 LAST BODY_TYPE PLUMBING
J 0
(-1200 1675);
DISPLAY 0.872340 (-1200 1675);
PAINT GREEN (-1200 1675);
DISPLAY INVISIBLE (-1200 1675);
FORCEPROP 1 LAST HDL_TAP TRUE
J 0
(-875 1500);
DISPLAY 0.872340 (-875 1500);
DISPLAY INVISIBLE (-875 1500);
FORCEPROP 1 LAST PATH I63
J 0
(-1202 1625);
DISPLAY 0.872340 (-1202 1625);
PAINT GREEN (-1202 1625);
DISPLAY INVISIBLE (-1202 1625);
FORCEADD TAP..1
(-1200 1675);
FORCEPROP 3 LASTPIN (-1250 1675) SIG_NAME M_D_CPU1_SB_DQ<12>
J 0
(-1240 1685);
DISPLAY 0.659574 (-1240 1685);
PAINT MONO (-1240 1685);
DISPLAY INVISIBLE (-1240 1685);
FORCEPROP 1 LASTPIN (-1250 1675) BN 12
J 0
(-1262 1683);
DISPLAY 0.680851 (-1262 1683);
PAINT GREEN (-1262 1683);
FORCEPROP 2 LAST CDS_LIB standard
J 0
(-1200 1675);
PAINT MONO (-1200 1675);
DISPLAY INVISIBLE (-1200 1675);
FORCEPROP 1 LAST BODY_TYPE PLUMBING
J 0
(-1200 1725);
DISPLAY 0.872340 (-1200 1725);
PAINT GREEN (-1200 1725);
DISPLAY INVISIBLE (-1200 1725);
FORCEPROP 1 LAST HDL_TAP TRUE
J 0
(-875 1550);
DISPLAY 0.872340 (-875 1550);
DISPLAY INVISIBLE (-875 1550);
FORCEPROP 1 LAST PATH I64
J 0
(-1202 1675);
DISPLAY 0.872340 (-1202 1675);
PAINT GREEN (-1202 1675);
DISPLAY INVISIBLE (-1202 1675);
FORCEADD TAP..1
(-1200 1725);
FORCEPROP 3 LASTPIN (-1250 1725) SIG_NAME M_D_CPU1_SB_DQ<13>
J 0
(-1240 1735);
DISPLAY 0.659574 (-1240 1735);
PAINT MONO (-1240 1735);
DISPLAY INVISIBLE (-1240 1735);
FORCEPROP 1 LASTPIN (-1250 1725) BN 13
J 0
(-1262 1733);
DISPLAY 0.680851 (-1262 1733);
PAINT GREEN (-1262 1733);
FORCEPROP 2 LAST CDS_LIB standard
J 0
(-1200 1725);
PAINT MONO (-1200 1725);
DISPLAY INVISIBLE (-1200 1725);
FORCEPROP 1 LAST BODY_TYPE PLUMBING
J 0
(-1200 1775);
DISPLAY 0.872340 (-1200 1775);
PAINT GREEN (-1200 1775);
DISPLAY INVISIBLE (-1200 1775);
FORCEPROP 1 LAST HDL_TAP TRUE
J 0
(-875 1600);
DISPLAY 0.872340 (-875 1600);
DISPLAY INVISIBLE (-875 1600);
FORCEPROP 1 LAST PATH I65
J 0
(-1202 1725);
DISPLAY 0.872340 (-1202 1725);
PAINT GREEN (-1202 1725);
DISPLAY INVISIBLE (-1202 1725);
FORCEADD TAP..1
(-1200 1775);
FORCEPROP 3 LASTPIN (-1250 1775) SIG_NAME M_D_CPU1_SB_DQ<14>
J 0
(-1240 1785);
DISPLAY 0.659574 (-1240 1785);
PAINT MONO (-1240 1785);
DISPLAY INVISIBLE (-1240 1785);
FORCEPROP 1 LASTPIN (-1250 1775) BN 14
J 0
(-1262 1783);
DISPLAY 0.680851 (-1262 1783);
PAINT GREEN (-1262 1783);
FORCEPROP 2 LAST CDS_LIB standard
J 0
(-1200 1775);
PAINT MONO (-1200 1775);
DISPLAY INVISIBLE (-1200 1775);
FORCEPROP 1 LAST BODY_TYPE PLUMBING
J 0
(-1200 1825);
DISPLAY 0.872340 (-1200 1825);
PAINT GREEN (-1200 1825);
DISPLAY INVISIBLE (-1200 1825);
FORCEPROP 1 LAST HDL_TAP TRUE
J 0
(-875 1650);
DISPLAY 0.872340 (-875 1650);
DISPLAY INVISIBLE (-875 1650);
FORCEPROP 1 LAST PATH I66
J 0
(-1202 1775);
DISPLAY 0.872340 (-1202 1775);
PAINT GREEN (-1202 1775);
DISPLAY INVISIBLE (-1202 1775);
FORCEADD TAP..1
(-1200 1825);
FORCEPROP 3 LASTPIN (-1250 1825) SIG_NAME M_D_CPU1_SB_DQ<15>
J 0
(-1240 1835);
DISPLAY 0.659574 (-1240 1835);
PAINT MONO (-1240 1835);
DISPLAY INVISIBLE (-1240 1835);
FORCEPROP 1 LASTPIN (-1250 1825) BN 15
J 0
(-1262 1833);
DISPLAY 0.680851 (-1262 1833);
PAINT GREEN (-1262 1833);
FORCEPROP 2 LAST CDS_LIB standard
J 0
(-1200 1825);
PAINT MONO (-1200 1825);
DISPLAY INVISIBLE (-1200 1825);
FORCEPROP 1 LAST BODY_TYPE PLUMBING
J 0
(-1200 1875);
DISPLAY 0.872340 (-1200 1875);
PAINT GREEN (-1200 1875);
DISPLAY INVISIBLE (-1200 1875);
FORCEPROP 1 LAST HDL_TAP TRUE
J 0
(-875 1700);
DISPLAY 0.872340 (-875 1700);
DISPLAY INVISIBLE (-875 1700);
FORCEPROP 1 LAST PATH I67
J 0
(-1202 1825);
DISPLAY 0.872340 (-1202 1825);
PAINT GREEN (-1202 1825);
DISPLAY INVISIBLE (-1202 1825);
FORCEADD TAP..1
(-1200 1925);
FORCEPROP 3 LASTPIN (-1250 1925) SIG_NAME M_D_CPU1_SB_DQ<17>
J 0
(-1240 1935);
DISPLAY 0.659574 (-1240 1935);
PAINT MONO (-1240 1935);
DISPLAY INVISIBLE (-1240 1935);
FORCEPROP 1 LASTPIN (-1250 1925) BN 17
J 0
(-1262 1933);
DISPLAY 0.680851 (-1262 1933);
PAINT GREEN (-1262 1933);
FORCEPROP 2 LAST CDS_LIB standard
J 0
(-1200 1925);
PAINT MONO (-1200 1925);
DISPLAY INVISIBLE (-1200 1925);
FORCEPROP 1 LAST BODY_TYPE PLUMBING
J 0
(-1200 1975);
DISPLAY 0.872340 (-1200 1975);
PAINT GREEN (-1200 1975);
DISPLAY INVISIBLE (-1200 1975);
FORCEPROP 1 LAST HDL_TAP TRUE
J 0
(-875 1800);
DISPLAY 0.872340 (-875 1800);
DISPLAY INVISIBLE (-875 1800);
FORCEPROP 1 LAST PATH I68
J 0
(-1202 1925);
DISPLAY 0.872340 (-1202 1925);
PAINT GREEN (-1202 1925);
DISPLAY INVISIBLE (-1202 1925);
FORCEADD TAP..1
(-1200 1875);
FORCEPROP 3 LASTPIN (-1250 1875) SIG_NAME M_D_CPU1_SB_DQ<16>
J 0
(-1240 1885);
DISPLAY 0.659574 (-1240 1885);
PAINT MONO (-1240 1885);
DISPLAY INVISIBLE (-1240 1885);
FORCEPROP 1 LASTPIN (-1250 1875) BN 16
J 0
(-1262 1883);
DISPLAY 0.680851 (-1262 1883);
PAINT GREEN (-1262 1883);
FORCEPROP 2 LAST CDS_LIB standard
J 0
(-1200 1875);
PAINT MONO (-1200 1875);
DISPLAY INVISIBLE (-1200 1875);
FORCEPROP 1 LAST BODY_TYPE PLUMBING
J 0
(-1200 1925);
DISPLAY 0.872340 (-1200 1925);
PAINT GREEN (-1200 1925);
DISPLAY INVISIBLE (-1200 1925);
FORCEPROP 1 LAST HDL_TAP TRUE
J 0
(-875 1750);
DISPLAY 0.872340 (-875 1750);
DISPLAY INVISIBLE (-875 1750);
FORCEPROP 1 LAST PATH I69
J 0
(-1202 1875);
DISPLAY 0.872340 (-1202 1875);
PAINT GREEN (-1202 1875);
DISPLAY INVISIBLE (-1202 1875);
FORCEADD TAP..1
(-1200 1975);
FORCEPROP 3 LASTPIN (-1250 1975) SIG_NAME M_D_CPU1_SB_DQ<18>
J 0
(-1240 1985);
DISPLAY 0.659574 (-1240 1985);
PAINT MONO (-1240 1985);
DISPLAY INVISIBLE (-1240 1985);
FORCEPROP 1 LASTPIN (-1250 1975) BN 18
J 0
(-1262 1983);
DISPLAY 0.680851 (-1262 1983);
PAINT GREEN (-1262 1983);
FORCEPROP 2 LAST CDS_LIB standard
J 0
(-1200 1975);
PAINT MONO (-1200 1975);
DISPLAY INVISIBLE (-1200 1975);
FORCEPROP 1 LAST BODY_TYPE PLUMBING
J 0
(-1200 2025);
DISPLAY 0.872340 (-1200 2025);
PAINT GREEN (-1200 2025);
DISPLAY INVISIBLE (-1200 2025);
FORCEPROP 1 LAST HDL_TAP TRUE
J 0
(-875 1850);
DISPLAY 0.872340 (-875 1850);
DISPLAY INVISIBLE (-875 1850);
FORCEPROP 1 LAST PATH I70
J 0
(-1202 1975);
DISPLAY 0.872340 (-1202 1975);
PAINT GREEN (-1202 1975);
DISPLAY INVISIBLE (-1202 1975);
FORCEADD TAP..1
(-1200 2025);
FORCEPROP 3 LASTPIN (-1250 2025) SIG_NAME M_D_CPU1_SB_DQ<19>
J 0
(-1240 2035);
DISPLAY 0.659574 (-1240 2035);
PAINT MONO (-1240 2035);
DISPLAY INVISIBLE (-1240 2035);
FORCEPROP 1 LASTPIN (-1250 2025) BN 19
J 0
(-1262 2033);
DISPLAY 0.680851 (-1262 2033);
PAINT GREEN (-1262 2033);
FORCEPROP 2 LAST CDS_LIB standard
J 0
(-1200 2025);
PAINT MONO (-1200 2025);
DISPLAY INVISIBLE (-1200 2025);
FORCEPROP 1 LAST BODY_TYPE PLUMBING
J 0
(-1200 2075);
DISPLAY 0.872340 (-1200 2075);
PAINT GREEN (-1200 2075);
DISPLAY INVISIBLE (-1200 2075);
FORCEPROP 1 LAST HDL_TAP TRUE
J 0
(-875 1900);
DISPLAY 0.872340 (-875 1900);
DISPLAY INVISIBLE (-875 1900);
FORCEPROP 1 LAST PATH I71
J 0
(-1202 2025);
DISPLAY 0.872340 (-1202 2025);
PAINT GREEN (-1202 2025);
DISPLAY INVISIBLE (-1202 2025);
FORCEADD TAP..1
(-1200 2075);
FORCEPROP 3 LASTPIN (-1250 2075) SIG_NAME M_D_CPU1_SB_DQ<20>
J 0
(-1240 2085);
DISPLAY 0.659574 (-1240 2085);
PAINT MONO (-1240 2085);
DISPLAY INVISIBLE (-1240 2085);
FORCEPROP 1 LASTPIN (-1250 2075) BN 20
J 0
(-1262 2083);
DISPLAY 0.680851 (-1262 2083);
PAINT GREEN (-1262 2083);
FORCEPROP 2 LAST CDS_LIB standard
J 0
(-1200 2075);
PAINT MONO (-1200 2075);
DISPLAY INVISIBLE (-1200 2075);
FORCEPROP 1 LAST BODY_TYPE PLUMBING
J 0
(-1200 2125);
DISPLAY 0.872340 (-1200 2125);
PAINT GREEN (-1200 2125);
DISPLAY INVISIBLE (-1200 2125);
FORCEPROP 1 LAST HDL_TAP TRUE
J 0
(-875 1950);
DISPLAY 0.872340 (-875 1950);
DISPLAY INVISIBLE (-875 1950);
FORCEPROP 1 LAST PATH I72
J 0
(-1202 2075);
DISPLAY 0.872340 (-1202 2075);
PAINT GREEN (-1202 2075);
DISPLAY INVISIBLE (-1202 2075);
FORCEADD TAP..1
(-1200 2125);
FORCEPROP 3 LASTPIN (-1250 2125) SIG_NAME M_D_CPU1_SB_DQ<21>
J 0
(-1240 2135);
DISPLAY 0.659574 (-1240 2135);
PAINT MONO (-1240 2135);
DISPLAY INVISIBLE (-1240 2135);
FORCEPROP 1 LASTPIN (-1250 2125) BN 21
J 0
(-1262 2133);
DISPLAY 0.680851 (-1262 2133);
PAINT GREEN (-1262 2133);
FORCEPROP 2 LAST CDS_LIB standard
J 0
(-1200 2125);
PAINT MONO (-1200 2125);
DISPLAY INVISIBLE (-1200 2125);
FORCEPROP 1 LAST BODY_TYPE PLUMBING
J 0
(-1200 2175);
DISPLAY 0.872340 (-1200 2175);
PAINT GREEN (-1200 2175);
DISPLAY INVISIBLE (-1200 2175);
FORCEPROP 1 LAST HDL_TAP TRUE
J 0
(-875 2000);
DISPLAY 0.872340 (-875 2000);
DISPLAY INVISIBLE (-875 2000);
FORCEPROP 1 LAST PATH I73
J 0
(-1202 2125);
DISPLAY 0.872340 (-1202 2125);
PAINT GREEN (-1202 2125);
DISPLAY INVISIBLE (-1202 2125);
FORCEADD TAP..1
(-1200 2175);
FORCEPROP 3 LASTPIN (-1250 2175) SIG_NAME M_D_CPU1_SB_DQ<22>
J 0
(-1240 2185);
DISPLAY 0.659574 (-1240 2185);
PAINT MONO (-1240 2185);
DISPLAY INVISIBLE (-1240 2185);
FORCEPROP 1 LASTPIN (-1250 2175) BN 22
J 0
(-1262 2183);
DISPLAY 0.680851 (-1262 2183);
PAINT GREEN (-1262 2183);
FORCEPROP 2 LAST CDS_LIB standard
J 0
(-1200 2175);
DISPLAY INVISIBLE (-1200 2175);
FORCEPROP 1 LAST BODY_TYPE PLUMBING
J 0
(-1200 2225);
DISPLAY 0.872340 (-1200 2225);
PAINT GREEN (-1200 2225);
DISPLAY INVISIBLE (-1200 2225);
FORCEPROP 1 LAST HDL_TAP TRUE
J 0
(-875 2050);
DISPLAY 0.872340 (-875 2050);
DISPLAY INVISIBLE (-875 2050);
FORCEPROP 1 LAST PATH I74
J 0
(-1202 2175);
DISPLAY 0.872340 (-1202 2175);
PAINT GREEN (-1202 2175);
DISPLAY INVISIBLE (-1202 2175);
FORCEADD TAP..1
(-1200 2225);
FORCEPROP 3 LASTPIN (-1250 2225) SIG_NAME M_D_CPU1_SB_DQ<23>
J 0
(-1240 2235);
DISPLAY 0.659574 (-1240 2235);
PAINT MONO (-1240 2235);
DISPLAY INVISIBLE (-1240 2235);
FORCEPROP 1 LASTPIN (-1250 2225) BN 23
J 0
(-1262 2233);
DISPLAY 0.680851 (-1262 2233);
PAINT GREEN (-1262 2233);
FORCEPROP 2 LAST CDS_LIB standard
J 0
(-1200 2225);
DISPLAY INVISIBLE (-1200 2225);
FORCEPROP 1 LAST BODY_TYPE PLUMBING
J 0
(-1200 2275);
DISPLAY 0.872340 (-1200 2275);
PAINT GREEN (-1200 2275);
DISPLAY INVISIBLE (-1200 2275);
FORCEPROP 1 LAST HDL_TAP TRUE
J 0
(-875 2100);
DISPLAY 0.872340 (-875 2100);
DISPLAY INVISIBLE (-875 2100);
FORCEPROP 1 LAST PATH I75
J 0
(-1202 2225);
DISPLAY 0.872340 (-1202 2225);
PAINT GREEN (-1202 2225);
DISPLAY INVISIBLE (-1202 2225);
FORCEADD TAP..1
(-1200 2275);
FORCEPROP 3 LASTPIN (-1250 2275) SIG_NAME M_D_CPU1_SB_DQ<24>
J 0
(-1240 2285);
DISPLAY 0.659574 (-1240 2285);
PAINT MONO (-1240 2285);
DISPLAY INVISIBLE (-1240 2285);
FORCEPROP 1 LASTPIN (-1250 2275) BN 24
J 0
(-1262 2283);
DISPLAY 0.680851 (-1262 2283);
PAINT GREEN (-1262 2283);
FORCEPROP 2 LAST CDS_LIB standard
J 0
(-1200 2275);
DISPLAY INVISIBLE (-1200 2275);
FORCEPROP 1 LAST BODY_TYPE PLUMBING
J 0
(-1200 2325);
DISPLAY 0.872340 (-1200 2325);
PAINT GREEN (-1200 2325);
DISPLAY INVISIBLE (-1200 2325);
FORCEPROP 1 LAST HDL_TAP TRUE
J 0
(-875 2150);
DISPLAY 0.872340 (-875 2150);
DISPLAY INVISIBLE (-875 2150);
FORCEPROP 1 LAST PATH I76
J 0
(-1202 2275);
DISPLAY 0.872340 (-1202 2275);
PAINT GREEN (-1202 2275);
DISPLAY INVISIBLE (-1202 2275);
FORCEADD TAP..1
(-1200 2375);
FORCEPROP 3 LASTPIN (-1250 2375) SIG_NAME M_D_CPU1_SB_DQ<26>
J 0
(-1240 2385);
DISPLAY 0.659574 (-1240 2385);
PAINT MONO (-1240 2385);
DISPLAY INVISIBLE (-1240 2385);
FORCEPROP 1 LASTPIN (-1250 2375) BN 26
J 0
(-1262 2383);
DISPLAY 0.680851 (-1262 2383);
PAINT GREEN (-1262 2383);
FORCEPROP 2 LAST CDS_LIB standard
J 0
(-1200 2375);
DISPLAY INVISIBLE (-1200 2375);
FORCEPROP 1 LAST BODY_TYPE PLUMBING
J 0
(-1200 2425);
DISPLAY 0.872340 (-1200 2425);
PAINT GREEN (-1200 2425);
DISPLAY INVISIBLE (-1200 2425);
FORCEPROP 1 LAST HDL_TAP TRUE
J 0
(-875 2250);
DISPLAY 0.872340 (-875 2250);
DISPLAY INVISIBLE (-875 2250);
FORCEPROP 1 LAST PATH I77
J 0
(-1202 2375);
DISPLAY 0.872340 (-1202 2375);
PAINT GREEN (-1202 2375);
DISPLAY INVISIBLE (-1202 2375);
FORCEADD TAP..1
(-1200 2325);
FORCEPROP 3 LASTPIN (-1250 2325) SIG_NAME M_D_CPU1_SB_DQ<25>
J 0
(-1240 2335);
DISPLAY 0.659574 (-1240 2335);
PAINT MONO (-1240 2335);
DISPLAY INVISIBLE (-1240 2335);
FORCEPROP 1 LASTPIN (-1250 2325) BN 25
J 0
(-1262 2333);
DISPLAY 0.680851 (-1262 2333);
PAINT GREEN (-1262 2333);
FORCEPROP 2 LAST CDS_LIB standard
J 0
(-1200 2325);
DISPLAY INVISIBLE (-1200 2325);
FORCEPROP 1 LAST BODY_TYPE PLUMBING
J 0
(-1200 2375);
DISPLAY 0.872340 (-1200 2375);
PAINT GREEN (-1200 2375);
DISPLAY INVISIBLE (-1200 2375);
FORCEPROP 1 LAST HDL_TAP TRUE
J 0
(-875 2200);
DISPLAY 0.872340 (-875 2200);
DISPLAY INVISIBLE (-875 2200);
FORCEPROP 1 LAST PATH I78
J 0
(-1202 2325);
DISPLAY 0.872340 (-1202 2325);
PAINT GREEN (-1202 2325);
DISPLAY INVISIBLE (-1202 2325);
FORCEADD TAP..1
(-1200 2425);
FORCEPROP 3 LASTPIN (-1250 2425) SIG_NAME M_D_CPU1_SB_DQ<27>
J 0
(-1240 2435);
DISPLAY 0.659574 (-1240 2435);
PAINT MONO (-1240 2435);
DISPLAY INVISIBLE (-1240 2435);
FORCEPROP 1 LASTPIN (-1250 2425) BN 27
J 0
(-1262 2433);
DISPLAY 0.680851 (-1262 2433);
PAINT GREEN (-1262 2433);
FORCEPROP 2 LAST CDS_LIB standard
J 0
(-1200 2425);
DISPLAY INVISIBLE (-1200 2425);
FORCEPROP 1 LAST BODY_TYPE PLUMBING
J 0
(-1200 2475);
DISPLAY 0.872340 (-1200 2475);
PAINT GREEN (-1200 2475);
DISPLAY INVISIBLE (-1200 2475);
FORCEPROP 1 LAST HDL_TAP TRUE
J 0
(-875 2300);
DISPLAY 0.872340 (-875 2300);
DISPLAY INVISIBLE (-875 2300);
FORCEPROP 1 LAST PATH I79
J 0
(-1202 2425);
DISPLAY 0.872340 (-1202 2425);
PAINT GREEN (-1202 2425);
DISPLAY INVISIBLE (-1202 2425);
FORCEADD OFFPAGE..1
(-3700 1725);
FORCEPROP 2 LAST $XR7 104 
J 0
(-4102 1761);
DISPLAY 0.638298 (-4102 1761);
PAINT MONO (-4102 1761);
FORCEPROP 2 LAST $XR6 103 
J 0
(-3982 1761);
DISPLAY 0.638298 (-3982 1761);
PAINT MONO (-3982 1761);
FORCEPROP 2 LAST $XR5 102 
J 0
(-4222 1689);
DISPLAY 0.638298 (-4222 1689);
PAINT MONO (-4222 1689);
FORCEPROP 2 LAST $XR4 101 
J 0
(-4102 1689);
DISPLAY 0.638298 (-4102 1689);
PAINT MONO (-4102 1689);
FORCEPROP 2 LAST $XR3 100 
J 0
(-3982 1689);
DISPLAY 0.638298 (-3982 1689);
PAINT MONO (-3982 1689);
FORCEPROP 2 LAST $XR2 99 
J 0
(-4162 1725);
DISPLAY 0.638298 (-4162 1725);
PAINT MONO (-4162 1725);
FORCEPROP 2 LAST $XR1 98 
J 0
(-4072 1725);
DISPLAY 0.638298 (-4072 1725);
PAINT MONO (-4072 1725);
FORCEPROP 2 LAST $XR0 230 
J 0
(-3982 1725);
DISPLAY 0.638298 (-3982 1725);
PAINT MONO (-3982 1725);
FORCEPROP 2 LAST CDS_LIB standard
J 0
(-3700 1725);
PAINT MONO (-3700 1725);
DISPLAY INVISIBLE (-3700 1725);
FORCEPROP 1 LAST OFFPAGE TRUE
J 0
(-3375 1600);
DISPLAY 0.872340 (-3375 1600);
DISPLAY INVISIBLE (-3375 1600);
FORCEPROP 1 LAST COMMENT_BODY TRUE
J 0
(-3575 1625);
DISPLAY 0.872340 (-3575 1625);
PAINT GREEN (-3575 1625);
DISPLAY INVISIBLE (-3575 1625);
FORCEPROP 2 LAST PATH I8
J 0
(-3650 1800);
DISPLAY 1.021277 (-3650 1800);
DISPLAY INVISIBLE (-3650 1800);
FORCEADD TAP..1
(-1200 2475);
FORCEPROP 3 LASTPIN (-1250 2475) SIG_NAME M_D_CPU1_SB_DQ<28>
J 0
(-1240 2485);
DISPLAY 0.659574 (-1240 2485);
PAINT MONO (-1240 2485);
DISPLAY INVISIBLE (-1240 2485);
FORCEPROP 1 LASTPIN (-1250 2475) BN 28
J 0
(-1262 2483);
DISPLAY 0.680851 (-1262 2483);
PAINT GREEN (-1262 2483);
FORCEPROP 2 LAST CDS_LIB standard
J 0
(-1200 2475);
DISPLAY INVISIBLE (-1200 2475);
FORCEPROP 1 LAST BODY_TYPE PLUMBING
J 0
(-1200 2525);
DISPLAY 0.872340 (-1200 2525);
PAINT GREEN (-1200 2525);
DISPLAY INVISIBLE (-1200 2525);
FORCEPROP 1 LAST HDL_TAP TRUE
J 0
(-875 2350);
DISPLAY 0.872340 (-875 2350);
DISPLAY INVISIBLE (-875 2350);
FORCEPROP 1 LAST PATH I80
J 0
(-1202 2475);
DISPLAY 0.872340 (-1202 2475);
PAINT GREEN (-1202 2475);
DISPLAY INVISIBLE (-1202 2475);
FORCEADD TAP..1
(-1200 2525);
FORCEPROP 3 LASTPIN (-1250 2525) SIG_NAME M_D_CPU1_SB_DQ<29>
J 0
(-1240 2535);
DISPLAY 0.659574 (-1240 2535);
PAINT MONO (-1240 2535);
DISPLAY INVISIBLE (-1240 2535);
FORCEPROP 1 LASTPIN (-1250 2525) BN 29
J 0
(-1262 2533);
DISPLAY 0.680851 (-1262 2533);
PAINT GREEN (-1262 2533);
FORCEPROP 2 LAST CDS_LIB standard
J 0
(-1200 2525);
DISPLAY INVISIBLE (-1200 2525);
FORCEPROP 1 LAST BODY_TYPE PLUMBING
J 0
(-1200 2575);
DISPLAY 0.872340 (-1200 2575);
PAINT GREEN (-1200 2575);
DISPLAY INVISIBLE (-1200 2575);
FORCEPROP 1 LAST HDL_TAP TRUE
J 0
(-875 2400);
DISPLAY 0.872340 (-875 2400);
DISPLAY INVISIBLE (-875 2400);
FORCEPROP 1 LAST PATH I81
J 0
(-1202 2525);
DISPLAY 0.872340 (-1202 2525);
PAINT GREEN (-1202 2525);
DISPLAY INVISIBLE (-1202 2525);
FORCEADD TAP..1
(-1200 2575);
FORCEPROP 3 LASTPIN (-1250 2575) SIG_NAME M_D_CPU1_SB_DQ<30>
J 0
(-1240 2585);
DISPLAY 0.659574 (-1240 2585);
PAINT MONO (-1240 2585);
DISPLAY INVISIBLE (-1240 2585);
FORCEPROP 1 LASTPIN (-1250 2575) BN 30
J 0
(-1262 2583);
DISPLAY 0.680851 (-1262 2583);
PAINT GREEN (-1262 2583);
FORCEPROP 2 LAST CDS_LIB standard
J 0
(-1200 2575);
DISPLAY INVISIBLE (-1200 2575);
FORCEPROP 1 LAST BODY_TYPE PLUMBING
J 0
(-1200 2625);
DISPLAY 0.872340 (-1200 2625);
PAINT GREEN (-1200 2625);
DISPLAY INVISIBLE (-1200 2625);
FORCEPROP 1 LAST HDL_TAP TRUE
J 0
(-875 2450);
DISPLAY 0.872340 (-875 2450);
DISPLAY INVISIBLE (-875 2450);
FORCEPROP 1 LAST PATH I82
J 0
(-1202 2575);
DISPLAY 0.872340 (-1202 2575);
PAINT GREEN (-1202 2575);
DISPLAY INVISIBLE (-1202 2575);
FORCEADD TAP..1
(-1200 2625);
FORCEPROP 3 LASTPIN (-1250 2625) SIG_NAME M_D_CPU1_SB_DQ<31>
J 0
(-1240 2635);
DISPLAY 0.659574 (-1240 2635);
PAINT MONO (-1240 2635);
DISPLAY INVISIBLE (-1240 2635);
FORCEPROP 1 LASTPIN (-1250 2625) BN 31
J 0
(-1262 2633);
DISPLAY 0.680851 (-1262 2633);
PAINT GREEN (-1262 2633);
FORCEPROP 2 LAST CDS_LIB standard
J 0
(-1200 2625);
DISPLAY INVISIBLE (-1200 2625);
FORCEPROP 1 LAST BODY_TYPE PLUMBING
J 0
(-1200 2675);
DISPLAY 0.872340 (-1200 2675);
PAINT GREEN (-1200 2675);
DISPLAY INVISIBLE (-1200 2675);
FORCEPROP 1 LAST HDL_TAP TRUE
J 0
(-875 2500);
DISPLAY 0.872340 (-875 2500);
DISPLAY INVISIBLE (-875 2500);
FORCEPROP 1 LAST PATH I83
J 0
(-1202 2625);
DISPLAY 0.872340 (-1202 2625);
PAINT GREEN (-1202 2625);
DISPLAY INVISIBLE (-1202 2625);
FORCEADD TAP..1
(-1200 2725);
FORCEPROP 3 LASTPIN (-1250 2725) SIG_NAME M_D_CPU1_SA_DQ<0>
J 0
(-1240 2735);
DISPLAY 0.659574 (-1240 2735);
PAINT MONO (-1240 2735);
DISPLAY INVISIBLE (-1240 2735);
FORCEPROP 1 LASTPIN (-1250 2725) BN 0
J 0
(-1262 2733);
DISPLAY 0.680851 (-1262 2733);
PAINT GREEN (-1262 2733);
FORCEPROP 2 LAST CDS_LIB standard
J 0
(-1200 2725);
PAINT MONO (-1200 2725);
DISPLAY INVISIBLE (-1200 2725);
FORCEPROP 1 LAST BODY_TYPE PLUMBING
J 0
(-1200 2775);
DISPLAY 0.872340 (-1200 2775);
PAINT GREEN (-1200 2775);
DISPLAY INVISIBLE (-1200 2775);
FORCEPROP 1 LAST HDL_TAP TRUE
J 0
(-875 2600);
DISPLAY 0.872340 (-875 2600);
DISPLAY INVISIBLE (-875 2600);
FORCEPROP 1 LAST PATH I84
J 0
(-1202 2725);
DISPLAY 0.872340 (-1202 2725);
PAINT GREEN (-1202 2725);
DISPLAY INVISIBLE (-1202 2725);
FORCEADD TAP..1
(-1200 2825);
FORCEPROP 3 LASTPIN (-1250 2825) SIG_NAME M_D_CPU1_SA_DQ<2>
J 0
(-1240 2835);
DISPLAY 0.659574 (-1240 2835);
PAINT MONO (-1240 2835);
DISPLAY INVISIBLE (-1240 2835);
FORCEPROP 1 LASTPIN (-1250 2825) BN 2
J 0
(-1262 2833);
DISPLAY 0.680851 (-1262 2833);
PAINT GREEN (-1262 2833);
FORCEPROP 2 LAST CDS_LIB standard
J 0
(-1200 2825);
PAINT MONO (-1200 2825);
DISPLAY INVISIBLE (-1200 2825);
FORCEPROP 1 LAST BODY_TYPE PLUMBING
J 0
(-1200 2875);
DISPLAY 0.872340 (-1200 2875);
PAINT GREEN (-1200 2875);
DISPLAY INVISIBLE (-1200 2875);
FORCEPROP 1 LAST HDL_TAP TRUE
J 0
(-875 2700);
DISPLAY 0.872340 (-875 2700);
DISPLAY INVISIBLE (-875 2700);
FORCEPROP 1 LAST PATH I85
J 0
(-1202 2825);
DISPLAY 0.872340 (-1202 2825);
PAINT GREEN (-1202 2825);
DISPLAY INVISIBLE (-1202 2825);
FORCEADD TAP..1
(-1200 2775);
FORCEPROP 3 LASTPIN (-1250 2775) SIG_NAME M_D_CPU1_SA_DQ<1>
J 0
(-1240 2785);
DISPLAY 0.659574 (-1240 2785);
PAINT MONO (-1240 2785);
DISPLAY INVISIBLE (-1240 2785);
FORCEPROP 1 LASTPIN (-1250 2775) BN 1
J 0
(-1262 2783);
DISPLAY 0.680851 (-1262 2783);
PAINT GREEN (-1262 2783);
FORCEPROP 2 LAST CDS_LIB standard
J 0
(-1200 2775);
PAINT MONO (-1200 2775);
DISPLAY INVISIBLE (-1200 2775);
FORCEPROP 1 LAST BODY_TYPE PLUMBING
J 0
(-1200 2825);
DISPLAY 0.872340 (-1200 2825);
PAINT GREEN (-1200 2825);
DISPLAY INVISIBLE (-1200 2825);
FORCEPROP 1 LAST HDL_TAP TRUE
J 0
(-875 2650);
DISPLAY 0.872340 (-875 2650);
DISPLAY INVISIBLE (-875 2650);
FORCEPROP 1 LAST PATH I86
J 0
(-1202 2775);
DISPLAY 0.872340 (-1202 2775);
PAINT GREEN (-1202 2775);
DISPLAY INVISIBLE (-1202 2775);
FORCEADD TAP..1
(-1200 2875);
FORCEPROP 3 LASTPIN (-1250 2875) SIG_NAME M_D_CPU1_SA_DQ<3>
J 0
(-1240 2885);
DISPLAY 0.659574 (-1240 2885);
PAINT MONO (-1240 2885);
DISPLAY INVISIBLE (-1240 2885);
FORCEPROP 1 LASTPIN (-1250 2875) BN 3
J 0
(-1262 2883);
DISPLAY 0.680851 (-1262 2883);
PAINT GREEN (-1262 2883);
FORCEPROP 2 LAST CDS_LIB standard
J 0
(-1200 2875);
PAINT MONO (-1200 2875);
DISPLAY INVISIBLE (-1200 2875);
FORCEPROP 1 LAST BODY_TYPE PLUMBING
J 0
(-1200 2925);
DISPLAY 0.872340 (-1200 2925);
PAINT GREEN (-1200 2925);
DISPLAY INVISIBLE (-1200 2925);
FORCEPROP 1 LAST HDL_TAP TRUE
J 0
(-875 2750);
DISPLAY 0.872340 (-875 2750);
DISPLAY INVISIBLE (-875 2750);
FORCEPROP 1 LAST PATH I87
J 0
(-1202 2875);
DISPLAY 0.872340 (-1202 2875);
PAINT GREEN (-1202 2875);
DISPLAY INVISIBLE (-1202 2875);
FORCEADD TAP..1
(-1200 2925);
FORCEPROP 3 LASTPIN (-1250 2925) SIG_NAME M_D_CPU1_SA_DQ<4>
J 0
(-1240 2935);
DISPLAY 0.659574 (-1240 2935);
PAINT MONO (-1240 2935);
DISPLAY INVISIBLE (-1240 2935);
FORCEPROP 1 LASTPIN (-1250 2925) BN 4
J 0
(-1262 2933);
DISPLAY 0.680851 (-1262 2933);
PAINT GREEN (-1262 2933);
FORCEPROP 2 LAST CDS_LIB standard
J 0
(-1200 2925);
PAINT MONO (-1200 2925);
DISPLAY INVISIBLE (-1200 2925);
FORCEPROP 1 LAST BODY_TYPE PLUMBING
J 0
(-1200 2975);
DISPLAY 0.872340 (-1200 2975);
PAINT GREEN (-1200 2975);
DISPLAY INVISIBLE (-1200 2975);
FORCEPROP 1 LAST HDL_TAP TRUE
J 0
(-875 2800);
DISPLAY 0.872340 (-875 2800);
DISPLAY INVISIBLE (-875 2800);
FORCEPROP 1 LAST PATH I88
J 0
(-1202 2925);
DISPLAY 0.872340 (-1202 2925);
PAINT GREEN (-1202 2925);
DISPLAY INVISIBLE (-1202 2925);
FORCEADD TAP..1
(-1200 2975);
FORCEPROP 3 LASTPIN (-1250 2975) SIG_NAME M_D_CPU1_SA_DQ<5>
J 0
(-1240 2985);
DISPLAY 0.659574 (-1240 2985);
PAINT MONO (-1240 2985);
DISPLAY INVISIBLE (-1240 2985);
FORCEPROP 1 LASTPIN (-1250 2975) BN 5
J 0
(-1262 2983);
DISPLAY 0.680851 (-1262 2983);
PAINT GREEN (-1262 2983);
FORCEPROP 2 LAST CDS_LIB standard
J 0
(-1200 2975);
PAINT MONO (-1200 2975);
DISPLAY INVISIBLE (-1200 2975);
FORCEPROP 1 LAST BODY_TYPE PLUMBING
J 0
(-1200 3025);
DISPLAY 0.872340 (-1200 3025);
PAINT GREEN (-1200 3025);
DISPLAY INVISIBLE (-1200 3025);
FORCEPROP 1 LAST HDL_TAP TRUE
J 0
(-875 2850);
DISPLAY 0.872340 (-875 2850);
DISPLAY INVISIBLE (-875 2850);
FORCEPROP 1 LAST PATH I89
J 0
(-1202 2975);
DISPLAY 0.872340 (-1202 2975);
PAINT GREEN (-1202 2975);
DISPLAY INVISIBLE (-1202 2975);
FORCEADD OFFPAGE..1
(-3700 1775);
FORCEPROP 2 LAST $XR0 105 
J 0
(-4192 1775);
DISPLAY 0.638298 (-4192 1775);
PAINT MONO (-4192 1775);
FORCEPROP 2 LAST CDS_LIB standard
J 0
(-3700 1775);
PAINT MONO (-3700 1775);
DISPLAY INVISIBLE (-3700 1775);
FORCEPROP 1 LAST OFFPAGE TRUE
J 0
(-3375 1650);
DISPLAY 0.872340 (-3375 1650);
DISPLAY INVISIBLE (-3375 1650);
FORCEPROP 1 LAST COMMENT_BODY TRUE
J 0
(-3575 1675);
DISPLAY 0.872340 (-3575 1675);
PAINT GREEN (-3575 1675);
DISPLAY INVISIBLE (-3575 1675);
FORCEPROP 2 LAST PATH I9
J 0
(-3650 1850);
DISPLAY 1.021277 (-3650 1850);
DISPLAY INVISIBLE (-3650 1850);
FORCEADD TAP..1
(-1200 3075);
FORCEPROP 3 LASTPIN (-1250 3075) SIG_NAME M_D_CPU1_SA_DQ<7>
J 0
(-1240 3085);
DISPLAY 0.659574 (-1240 3085);
PAINT MONO (-1240 3085);
DISPLAY INVISIBLE (-1240 3085);
FORCEPROP 1 LASTPIN (-1250 3075) BN 7
J 0
(-1262 3083);
DISPLAY 0.680851 (-1262 3083);
PAINT GREEN (-1262 3083);
FORCEPROP 2 LAST CDS_LIB standard
J 0
(-1200 3075);
PAINT MONO (-1200 3075);
DISPLAY INVISIBLE (-1200 3075);
FORCEPROP 1 LAST BODY_TYPE PLUMBING
J 0
(-1200 3125);
DISPLAY 0.872340 (-1200 3125);
PAINT GREEN (-1200 3125);
DISPLAY INVISIBLE (-1200 3125);
FORCEPROP 1 LAST HDL_TAP TRUE
J 0
(-875 2950);
DISPLAY 0.872340 (-875 2950);
DISPLAY INVISIBLE (-875 2950);
FORCEPROP 1 LAST PATH I90
J 0
(-1202 3075);
DISPLAY 0.872340 (-1202 3075);
PAINT GREEN (-1202 3075);
DISPLAY INVISIBLE (-1202 3075);
FORCEADD TAP..1
(-1200 3125);
FORCEPROP 3 LASTPIN (-1250 3125) SIG_NAME M_D_CPU1_SA_DQ<8>
J 0
(-1240 3135);
DISPLAY 0.659574 (-1240 3135);
PAINT MONO (-1240 3135);
DISPLAY INVISIBLE (-1240 3135);
FORCEPROP 1 LASTPIN (-1250 3125) BN 8
J 0
(-1262 3133);
DISPLAY 0.680851 (-1262 3133);
PAINT GREEN (-1262 3133);
FORCEPROP 2 LAST CDS_LIB standard
J 0
(-1200 3125);
PAINT MONO (-1200 3125);
DISPLAY INVISIBLE (-1200 3125);
FORCEPROP 1 LAST BODY_TYPE PLUMBING
J 0
(-1200 3175);
DISPLAY 0.872340 (-1200 3175);
PAINT GREEN (-1200 3175);
DISPLAY INVISIBLE (-1200 3175);
FORCEPROP 1 LAST HDL_TAP TRUE
J 0
(-875 3000);
DISPLAY 0.872340 (-875 3000);
DISPLAY INVISIBLE (-875 3000);
FORCEPROP 1 LAST PATH I91
J 0
(-1202 3125);
DISPLAY 0.872340 (-1202 3125);
PAINT GREEN (-1202 3125);
DISPLAY INVISIBLE (-1202 3125);
FORCEADD TAP..1
(-1200 3025);
FORCEPROP 3 LASTPIN (-1250 3025) SIG_NAME M_D_CPU1_SA_DQ<6>
J 0
(-1240 3035);
DISPLAY 0.659574 (-1240 3035);
PAINT MONO (-1240 3035);
DISPLAY INVISIBLE (-1240 3035);
FORCEPROP 1 LASTPIN (-1250 3025) BN 6
J 0
(-1262 3033);
DISPLAY 0.680851 (-1262 3033);
PAINT GREEN (-1262 3033);
FORCEPROP 2 LAST CDS_LIB standard
J 0
(-1200 3025);
PAINT MONO (-1200 3025);
DISPLAY INVISIBLE (-1200 3025);
FORCEPROP 1 LAST BODY_TYPE PLUMBING
J 0
(-1200 3075);
DISPLAY 0.872340 (-1200 3075);
PAINT GREEN (-1200 3075);
DISPLAY INVISIBLE (-1200 3075);
FORCEPROP 1 LAST HDL_TAP TRUE
J 0
(-875 2900);
DISPLAY 0.872340 (-875 2900);
DISPLAY INVISIBLE (-875 2900);
FORCEPROP 1 LAST PATH I92
J 0
(-1202 3025);
DISPLAY 0.872340 (-1202 3025);
PAINT GREEN (-1202 3025);
DISPLAY INVISIBLE (-1202 3025);
FORCEADD TAP..1
(-1200 3175);
FORCEPROP 3 LASTPIN (-1250 3175) SIG_NAME M_D_CPU1_SA_DQ<9>
J 0
(-1240 3185);
DISPLAY 0.659574 (-1240 3185);
PAINT MONO (-1240 3185);
DISPLAY INVISIBLE (-1240 3185);
FORCEPROP 1 LASTPIN (-1250 3175) BN 9
J 0
(-1262 3183);
DISPLAY 0.680851 (-1262 3183);
PAINT GREEN (-1262 3183);
FORCEPROP 2 LAST CDS_LIB standard
J 0
(-1200 3175);
PAINT MONO (-1200 3175);
DISPLAY INVISIBLE (-1200 3175);
FORCEPROP 1 LAST BODY_TYPE PLUMBING
J 0
(-1200 3225);
DISPLAY 0.872340 (-1200 3225);
PAINT GREEN (-1200 3225);
DISPLAY INVISIBLE (-1200 3225);
FORCEPROP 1 LAST HDL_TAP TRUE
J 0
(-875 3050);
DISPLAY 0.872340 (-875 3050);
DISPLAY INVISIBLE (-875 3050);
FORCEPROP 1 LAST PATH I93
J 0
(-1202 3175);
DISPLAY 0.872340 (-1202 3175);
PAINT GREEN (-1202 3175);
DISPLAY INVISIBLE (-1202 3175);
FORCEADD TAP..1
(-1200 3225);
FORCEPROP 3 LASTPIN (-1250 3225) SIG_NAME M_D_CPU1_SA_DQ<10>
J 0
(-1240 3235);
DISPLAY 0.659574 (-1240 3235);
PAINT MONO (-1240 3235);
DISPLAY INVISIBLE (-1240 3235);
FORCEPROP 1 LASTPIN (-1250 3225) BN 10
J 0
(-1262 3233);
DISPLAY 0.680851 (-1262 3233);
PAINT GREEN (-1262 3233);
FORCEPROP 2 LAST CDS_LIB standard
J 0
(-1200 3225);
PAINT MONO (-1200 3225);
DISPLAY INVISIBLE (-1200 3225);
FORCEPROP 1 LAST BODY_TYPE PLUMBING
J 0
(-1200 3275);
DISPLAY 0.872340 (-1200 3275);
PAINT GREEN (-1200 3275);
DISPLAY INVISIBLE (-1200 3275);
FORCEPROP 1 LAST HDL_TAP TRUE
J 0
(-875 3100);
DISPLAY 0.872340 (-875 3100);
DISPLAY INVISIBLE (-875 3100);
FORCEPROP 1 LAST PATH I94
J 0
(-1202 3225);
DISPLAY 0.872340 (-1202 3225);
PAINT GREEN (-1202 3225);
DISPLAY INVISIBLE (-1202 3225);
FORCEADD TAP..1
(-1200 3275);
FORCEPROP 3 LASTPIN (-1250 3275) SIG_NAME M_D_CPU1_SA_DQ<11>
J 0
(-1240 3285);
DISPLAY 0.659574 (-1240 3285);
PAINT MONO (-1240 3285);
DISPLAY INVISIBLE (-1240 3285);
FORCEPROP 1 LASTPIN (-1250 3275) BN 11
J 0
(-1262 3283);
DISPLAY 0.680851 (-1262 3283);
PAINT GREEN (-1262 3283);
FORCEPROP 2 LAST CDS_LIB standard
J 0
(-1200 3275);
PAINT MONO (-1200 3275);
DISPLAY INVISIBLE (-1200 3275);
FORCEPROP 1 LAST BODY_TYPE PLUMBING
J 0
(-1200 3325);
DISPLAY 0.872340 (-1200 3325);
PAINT GREEN (-1200 3325);
DISPLAY INVISIBLE (-1200 3325);
FORCEPROP 1 LAST HDL_TAP TRUE
J 0
(-875 3150);
DISPLAY 0.872340 (-875 3150);
DISPLAY INVISIBLE (-875 3150);
FORCEPROP 1 LAST PATH I95
J 0
(-1202 3275);
DISPLAY 0.872340 (-1202 3275);
PAINT GREEN (-1202 3275);
DISPLAY INVISIBLE (-1202 3275);
FORCEADD TAP..1
(-1200 3325);
FORCEPROP 3 LASTPIN (-1250 3325) SIG_NAME M_D_CPU1_SA_DQ<12>
J 0
(-1240 3335);
DISPLAY 0.659574 (-1240 3335);
PAINT MONO (-1240 3335);
DISPLAY INVISIBLE (-1240 3335);
FORCEPROP 1 LASTPIN (-1250 3325) BN 12
J 0
(-1262 3333);
DISPLAY 0.680851 (-1262 3333);
PAINT GREEN (-1262 3333);
FORCEPROP 2 LAST CDS_LIB standard
J 0
(-1200 3325);
PAINT MONO (-1200 3325);
DISPLAY INVISIBLE (-1200 3325);
FORCEPROP 1 LAST BODY_TYPE PLUMBING
J 0
(-1200 3375);
DISPLAY 0.872340 (-1200 3375);
PAINT GREEN (-1200 3375);
DISPLAY INVISIBLE (-1200 3375);
FORCEPROP 1 LAST HDL_TAP TRUE
J 0
(-875 3200);
DISPLAY 0.872340 (-875 3200);
DISPLAY INVISIBLE (-875 3200);
FORCEPROP 1 LAST PATH I96
J 0
(-1202 3325);
DISPLAY 0.872340 (-1202 3325);
PAINT GREEN (-1202 3325);
DISPLAY INVISIBLE (-1202 3325);
FORCEADD TAP..1
(-1200 3375);
FORCEPROP 3 LASTPIN (-1250 3375) SIG_NAME M_D_CPU1_SA_DQ<13>
J 0
(-1240 3385);
DISPLAY 0.659574 (-1240 3385);
PAINT MONO (-1240 3385);
DISPLAY INVISIBLE (-1240 3385);
FORCEPROP 1 LASTPIN (-1250 3375) BN 13
J 0
(-1262 3383);
DISPLAY 0.680851 (-1262 3383);
PAINT GREEN (-1262 3383);
FORCEPROP 2 LAST CDS_LIB standard
J 0
(-1200 3375);
PAINT MONO (-1200 3375);
DISPLAY INVISIBLE (-1200 3375);
FORCEPROP 1 LAST BODY_TYPE PLUMBING
J 0
(-1200 3425);
DISPLAY 0.872340 (-1200 3425);
PAINT GREEN (-1200 3425);
DISPLAY INVISIBLE (-1200 3425);
FORCEPROP 1 LAST HDL_TAP TRUE
J 0
(-875 3250);
DISPLAY 0.872340 (-875 3250);
DISPLAY INVISIBLE (-875 3250);
FORCEPROP 1 LAST PATH I97
J 0
(-1202 3375);
DISPLAY 0.872340 (-1202 3375);
PAINT GREEN (-1202 3375);
DISPLAY INVISIBLE (-1202 3375);
FORCEADD TAP..1
(-1200 3425);
FORCEPROP 3 LASTPIN (-1250 3425) SIG_NAME M_D_CPU1_SA_DQ<14>
J 0
(-1240 3435);
DISPLAY 0.659574 (-1240 3435);
PAINT MONO (-1240 3435);
DISPLAY INVISIBLE (-1240 3435);
FORCEPROP 1 LASTPIN (-1250 3425) BN 14
J 0
(-1262 3433);
DISPLAY 0.680851 (-1262 3433);
PAINT GREEN (-1262 3433);
FORCEPROP 2 LAST CDS_LIB standard
J 0
(-1200 3425);
PAINT MONO (-1200 3425);
DISPLAY INVISIBLE (-1200 3425);
FORCEPROP 1 LAST BODY_TYPE PLUMBING
J 0
(-1200 3475);
DISPLAY 0.872340 (-1200 3475);
PAINT GREEN (-1200 3475);
DISPLAY INVISIBLE (-1200 3475);
FORCEPROP 1 LAST HDL_TAP TRUE
J 0
(-875 3300);
DISPLAY 0.872340 (-875 3300);
DISPLAY INVISIBLE (-875 3300);
FORCEPROP 1 LAST PATH I98
J 0
(-1202 3425);
DISPLAY 0.872340 (-1202 3425);
PAINT GREEN (-1202 3425);
DISPLAY INVISIBLE (-1202 3425);
FORCEADD TAP..1
(-1200 3525);
FORCEPROP 3 LASTPIN (-1250 3525) SIG_NAME M_D_CPU1_SA_DQ<16>
J 0
(-1240 3535);
DISPLAY 0.659574 (-1240 3535);
PAINT MONO (-1240 3535);
DISPLAY INVISIBLE (-1240 3535);
FORCEPROP 1 LASTPIN (-1250 3525) BN 16
J 0
(-1262 3533);
DISPLAY 0.680851 (-1262 3533);
PAINT GREEN (-1262 3533);
FORCEPROP 2 LAST CDS_LIB standard
J 0
(-1200 3525);
PAINT MONO (-1200 3525);
DISPLAY INVISIBLE (-1200 3525);
FORCEPROP 1 LAST BODY_TYPE PLUMBING
J 0
(-1200 3575);
DISPLAY 0.872340 (-1200 3575);
PAINT GREEN (-1200 3575);
DISPLAY INVISIBLE (-1200 3575);
FORCEPROP 1 LAST HDL_TAP TRUE
J 0
(-875 3400);
DISPLAY 0.872340 (-875 3400);
DISPLAY INVISIBLE (-875 3400);
FORCEPROP 1 LAST PATH I99
J 0
(-1202 3525);
DISPLAY 0.872340 (-1202 3525);
PAINT GREEN (-1202 3525);
DISPLAY INVISIBLE (-1202 3525);
FORCEADD CAD_NOTE..1
(650 -175);
FORCEPROP 0 LAST S1 PLACE THE BYPASS CAPS CLOSE TO DIMM
J 0
(525 -300);
DISPLAY 1.021277 (525 -300);
PAINT WHITE (525 -300);
FORCEPROP 2 LAST CDS_LIB logical_power
J 0
(650 -175);
PAINT MONO (650 -175);
DISPLAY INVISIBLE (650 -175);
FORCEPROP 1 LAST COMMENT_BODY TRUE
J 0
(675 -75);
DISPLAY 0.978723 (675 -75);
DISPLAY INVISIBLE (675 -75);
FORCEADD QUANTA_TITLE_BLOCK_C..1
(5125 -1475);
FORCEPROP 0 LAST CDS_CON_LAST_MODIFIED Fri Aug 25 14:01:25 2023
J 0
(3240 -1460);
PAINT MONO (3240 -1460);
DISPLAY INVISIBLE (3240 -1460);
FORCEPROP 1 LAST CUSTOM_TXT_CDS <CON_LAST_MODIFIED>
J 0
(3240 -1460);
DISPLAY 0.978723 (3240 -1460);
FORCEPROP 2 LAST CUSTOM_TXT_CDS <XR_PAGE_TITLE>
J 0
(-2765 3775);
DISPLAY 0.638298 (-2765 3775);
PAINT PINK (-2765 3775);
DISPLAY INVISIBLE (-2765 3775);
FORCEPROP 2 LAST CUSTOM_TXT_CDS <Q_NUMBER>
J 0
(3722 -1372);
DISPLAY 1.212766 (3722 -1372);
FORCEPROP 1 LAST CUSTOM_TXT_CDS <NAME_2>
J 0
(1950 -1425);
FORCEPROP 1 LAST CUSTOM_TXT_CDS <NAME_1>
J 0
(1950 -1300);
FORCEPROP 1 LAST CUSTOM_TXT_CDS <Q_PROJ>
J 0
(2743 -1373);
DISPLAY 1.212766 (2743 -1373);
FORCEPROP 1 LAST CUSTOM_TXT_CDS <Q_REV>
J 0
(4941 -1372);
DISPLAY 1.212766 (4941 -1372);
FORCEPROP 1 LAST CUSTOM_TXT_CDS <CON_PAGE_NUM> OF <CON_TOTAL_PAGES>
J 0
(4679 -1457);
DISPLAY 0.978723 (4679 -1457);
FORCEPROP 1 LAST Q_TITLE DDR5 - CPU1 CHD DIMM2(BLACK)
J 0
(-4241 -1449);
DISPLAY 2.446809 (-4241 -1449);
PAINT GREEN (-4241 -1449);
FORCEPROP 1 LAST Q_DEPT 
J 1
(1362 -1426);
DISPLAY 1.957447 (1362 -1426);
PAINT GREEN (1362 -1426);
FORCEPROP 2 LAST CDS_XR_PAGE_TITLE CR-105 : @S9S_MB_2U_LIB.S9S_MB_2U(SCH_1):PAGE105
J 0
(-2765 3775);
DISPLAY 0.638298 (-2765 3775);
PAINT PINK (-2765 3775);
DISPLAY INVISIBLE (-2765 3775);
FORCEPROP 1 LAST COMMENT_BODY TRUE
J 0
(5137 -1488);
DISPLAY 0.978723 (5137 -1488);
PAINT GREEN (5137 -1488);
DISPLAY INVISIBLE (5137 -1488);
FORCEPROP 2 LAST PAGE_BORDER TRUE
J 0
(-2765 3775);
DISPLAY 0.638298 (-2765 3775);
PAINT PINK (-2765 3775);
DISPLAY INVISIBLE (-2765 3775);
FORCEPROP 1 LAST CDS_LMAN_SYM_OUTLINE -9475,6775,100,-125
J 0
(5125 -1475);
DISPLAY 0.468085 (5125 -1475);
PAINT GREEN (5125 -1475);
DISPLAY INVISIBLE (5125 -1475);
FORCEPROP 2 LAST CDS_LIB pure_quanta
J 0
(5125 -1475);
PAINT MONO (5125 -1475);
DISPLAY INVISIBLE (5125 -1475);
WIRE 17 -1 (-1150 4300)(-425 4300);
FORCEPROP 2 LAST SIG_NAME M_D_CPU1_SA_DQ<31:0>
J 0
(-1085 4310);
DISPLAY 0.680851 (-1085 4310);
PAINT WHITE (-1085 4310);
WIRE 17 -1 (-3725 2900)(-2900 2900);
FORCEPROP 2 LAST SIG_NAME M_D_CPU1_SA_CB<7:0>
J 0
(-3635 2910);
DISPLAY 0.680851 (-3635 2910);
PAINT WHITE (-3635 2910);
WIRE 17 -1 (-2900 2750)(-2900 2800);
WIRE 17 -1 (-2900 2700)(-2900 2750);
WIRE 17 -1 (-2900 2800)(-2900 2850);
WIRE 17 -1 (-2900 2850)(-2900 2900);
WIRE 17 -1 (-2900 2650)(-2900 2700);
WIRE 17 -1 (-2900 2600)(-2900 2650);
WIRE 17 -1 (-2900 2550)(-2900 2600);
WIRE 17 -1 (-3725 2450)(-2900 2450);
FORCEPROP 2 LAST SIG_NAME M_D_CPU1_SB_CB<7:0>
J 0
(-3635 2460);
DISPLAY 0.680851 (-3635 2460);
PAINT WHITE (-3635 2460);
WIRE 17 -1 (-2900 4000)(-2900 4050);
WIRE 17 -1 (-2900 4050)(-2900 4100);
WIRE 17 -1 (-2900 4100)(-2900 4150);
WIRE 17 -1 (-2900 4150)(-2900 4200);
WIRE 17 -1 (-2900 4200)(-2900 4250);
WIRE 17 -1 (-2900 4250)(-2900 4300);
WIRE 17 -1 (-3725 4300)(-2900 4300);
FORCEPROP 2 LAST SIG_NAME M_D_CPU1_SA_CA<6:0>
J 0
(-3635 4310);
DISPLAY 0.680851 (-3635 4310);
PAINT WHITE (-3635 4310);
WIRE 17 -1 (-2900 3600)(-2900 3650);
WIRE 17 -1 (-2900 3650)(-2900 3700);
WIRE 17 -1 (-2900 3700)(-2900 3750);
WIRE 17 -1 (-2900 3750)(-2900 3800);
WIRE 17 -1 (-2900 3800)(-2900 3850);
WIRE 17 -1 (-2900 3850)(-2900 3900);
WIRE 17 -1 (-3725 3900)(-2900 3900);
FORCEPROP 2 LAST SIG_NAME M_D_CPU1_SB_CA<6:0>
J 0
(-3635 3910);
DISPLAY 0.680851 (-3635 3910);
PAINT WHITE (-3635 3910);
WIRE 17 -1 (-2900 2400)(-2900 2450);
WIRE 17 -1 (-2900 2350)(-2900 2400);
WIRE 17 -1 (-2900 2300)(-2900 2350);
WIRE 17 -1 (-2900 2250)(-2900 2300);
WIRE 17 -1 (-2900 2200)(-2900 2250);
WIRE 17 -1 (-2900 2150)(-2900 2200);
WIRE 17 -1 (-2900 2100)(-2900 2150);
WIRE 17 -1 (-1150 4150)(-1150 4200);
WIRE 17 -1 (-1150 4100)(-1150 4150);
WIRE 17 -1 (-1150 4200)(-1150 4250);
WIRE 17 -1 (-1150 4250)(-1150 4300);
WIRE 17 -1 (-1150 4050)(-1150 4100);
WIRE 17 -1 (-1150 4000)(-1150 4050);
WIRE 17 -1 (-1150 3950)(-1150 4000);
WIRE 17 -1 (-1150 3900)(-1150 3950);
WIRE 17 -1 (-1150 3850)(-1150 3900);
WIRE 17 -1 (-1150 3800)(-1150 3850);
WIRE 17 -1 (-1150 3750)(-1150 3800);
WIRE 17 -1 (-1150 3700)(-1150 3750);
WIRE 17 -1 (-1150 3650)(-1150 3700);
WIRE 17 -1 (-1150 3600)(-1150 3650);
WIRE 17 -1 (-1150 3550)(-1150 3600);
WIRE 17 -1 (-1150 3500)(-1150 3550);
WIRE 17 -1 (-1150 3450)(-1150 3500);
WIRE 17 -1 (-1150 3400)(-1150 3450);
WIRE 17 -1 (-1150 3350)(-1150 3400);
WIRE 17 -1 (-1150 3300)(-1150 3350);
WIRE 17 -1 (-1150 3250)(-1150 3300);
WIRE 17 -1 (-1150 3200)(-1150 3250);
WIRE 17 -1 (-1150 3150)(-1150 3200);
WIRE 17 -1 (-1150 3100)(-1150 3150);
WIRE 17 -1 (-1150 3050)(-1150 3100);
WIRE 17 -1 (-1150 3000)(-1150 3050);
WIRE 17 -1 (-1150 2950)(-1150 3000);
WIRE 17 -1 (-1150 2900)(-1150 2950);
WIRE 17 -1 (-1150 2850)(-1150 2900);
WIRE 17 -1 (-1150 2800)(-1150 2850);
WIRE 17 -1 (-1150 2750)(-1150 2800);
WIRE 17 -1 (-1150 2650)(-425 2650);
FORCEPROP 2 LAST SIG_NAME M_D_CPU1_SB_DQ<31:0>
J 0
(-1085 2660);
DISPLAY 0.680851 (-1085 2660);
PAINT WHITE (-1085 2660);
WIRE 17 -1 (-1150 2600)(-1150 2650);
WIRE 17 -1 (-1150 2550)(-1150 2600);
WIRE 17 -1 (-1150 2500)(-1150 2550);
WIRE 17 -1 (-1150 2450)(-1150 2500);
WIRE 17 -1 (-1150 2400)(-1150 2450);
WIRE 17 -1 (-1150 2350)(-1150 2400);
WIRE 17 -1 (-1150 2300)(-1150 2350);
WIRE 17 -1 (-1150 2250)(-1150 2300);
WIRE 17 -1 (-1150 2200)(-1150 2250);
WIRE 17 -1 (-1150 2150)(-1150 2200);
WIRE 17 -1 (-1150 2100)(-1150 2150);
WIRE 17 -1 (-1150 2050)(-1150 2100);
WIRE 17 -1 (-1150 2000)(-1150 2050);
WIRE 17 -1 (-1150 1950)(-1150 2000);
WIRE 17 -1 (-1150 1900)(-1150 1950);
WIRE 17 -1 (-1150 1850)(-1150 1900);
WIRE 17 -1 (-1150 1800)(-1150 1850);
WIRE 17 -1 (-1150 1750)(-1150 1800);
WIRE 17 -1 (-1150 1700)(-1150 1750);
WIRE 17 -1 (-1150 1650)(-1150 1700);
WIRE 17 -1 (-1150 1600)(-1150 1650);
WIRE 17 -1 (-1150 1550)(-1150 1600);
WIRE 17 -1 (-1150 1500)(-1150 1550);
WIRE 17 -1 (-1150 1450)(-1150 1500);
WIRE 17 -1 (-1150 1400)(-1150 1450);
WIRE 17 -1 (-1150 1350)(-1150 1400);
WIRE 17 -1 (-1150 1300)(-1150 1350);
WIRE 17 -1 (-1150 1250)(-1150 1300);
WIRE 17 -1 (-1150 1200)(-1150 1250);
WIRE 17 -1 (-1150 1150)(-1150 1200);
WIRE 17 -1 (-1150 1100)(-1150 1150);
WIRE 17 -1 (1600 2950)(1600 3050);
WIRE 17 -1 (1600 2850)(1600 2950);
WIRE 17 -1 (1600 3050)(1600 3150);
WIRE 17 -1 (1600 3150)(1600 3250);
WIRE 17 -1 (1600 2750)(1600 2850);
WIRE 17 -1 (1600 2750)(1600 2650);
WIRE 17 -1 (1600 3250)(2625 3250);
FORCEPROP 2 LAST SIG_NAME M_D_CPU1_SB_DQS_DP<9:0>
J 0
(1840 3260);
DISPLAY 0.680851 (1840 3260);
PAINT WHITE (1840 3260);
WIRE 17 -1 (1600 2550)(1600 2650);
WIRE 17 -1 (1600 2450)(1600 2550);
WIRE 17 -1 (1600 2350)(1600 2450);
WIRE 17 -1 (1600 3900)(1600 4000);
WIRE 17 -1 (1600 3800)(1600 3900);
WIRE 17 -1 (1600 4000)(1600 4100);
WIRE 17 -1 (1600 4100)(1600 4200);
WIRE 17 -1 (1600 3800)(1600 3700);
WIRE 17 -1 (1600 3600)(1600 3700);
WIRE 17 -1 (1600 4200)(1600 4300);
WIRE 17 -1 (1600 4300)(2625 4300);
FORCEPROP 2 LAST SIG_NAME M_D_CPU1_SA_DQS_DP<9:0>
J 0
(1840 4310);
DISPLAY 0.680851 (1840 4310);
PAINT WHITE (1840 4310);
WIRE 17 -1 (1600 3500)(1600 3600);
WIRE 17 -1 (1600 3400)(1600 3500);
WIRE 17 -1 (1775 2300)(1775 2400);
WIRE 17 -1 (1775 2400)(1775 2500);
WIRE 17 -1 (1775 2500)(1775 2600);
WIRE 17 -1 (1775 2700)(1775 2600);
WIRE 17 -1 (1775 2700)(1775 2800);
WIRE 17 -1 (1775 2800)(1775 2900);
WIRE 17 -1 (1775 2900)(1775 3000);
WIRE 17 -1 (1775 3000)(1775 3100);
WIRE 17 -1 (1775 3100)(1775 3200);
WIRE 17 -1 (1775 3200)(2625 3200);
FORCEPROP 2 LAST SIG_NAME M_D_CPU1_SB_DQS_DN<9:0>
J 0
(1840 3210);
DISPLAY 0.680851 (1840 3210);
PAINT WHITE (1840 3210);
WIRE 17 -1 (1775 3350)(1775 3450);
WIRE 17 -1 (1775 3450)(1775 3550);
WIRE 17 -1 (1775 3550)(1775 3650);
WIRE 17 -1 (1775 3750)(1775 3650);
WIRE 17 -1 (1775 3750)(1775 3850);
WIRE 17 -1 (1775 3850)(1775 3950);
WIRE 17 -1 (1775 3950)(1775 4050);
WIRE 17 -1 (1775 4050)(1775 4150);
WIRE 17 -1 (1775 4150)(1775 4250);
WIRE 17 -1 (1775 4250)(2625 4250);
FORCEPROP 2 LAST SIG_NAME M_D_CPU1_SA_DQS_DN<9:0>
J 0
(1840 4260);
DISPLAY 0.680851 (1840 4260);
PAINT WHITE (1840 4260);
WIRE 16 -1 (525 500)(525 675);
WIRE 16 -1 (1525 675)(1525 625);
WIRE 16 -1 (3225 4775)(3225 4275);
WIRE 16 -1 (-3675 2100)(-3675 1825);
WIRE 16 -1 (-2625 -50)(-2625 25);
WIRE 16 -1 (525 300)(525 75);
WIRE 16 -1 (2150 75)(2150 150);
WIRE 16 -1 (3225 625)(3225 1025);
WIRE 16 -1 (4925 925)(4925 625);
WIRE 16 -1 (4925 975)(4925 925);
WIRE 16 -1 (4675 925)(4925 925);
WIRE 16 3135 (175 900)(175 -400);
WIRE 16 3135 (2775 900)(175 900);
WIRE 16 3135 (175 -400)(2775 -400);
WIRE 16 3135 (2775 -400)(2775 900);
WIRE 16 -1 (-1425 1275)(-1250 1275);
WIRE 16 -1 (-2500 1525)(-2575 1525);
WIRE 16 -1 (-3750 1575)(-2500 1575);
FORCEPROP 2 LAST SIG_NAME I3C_SPD_DDRABCD_CPU1_LVC1_SCL
J 0
(-3610 1585);
DISPLAY 0.680851 (-3610 1585);
PAINT WHITE (-3610 1585);
WIRE 16 -1 (-2500 1575)(-2500 1525);
WIRE 16 -1 (-4150 1575)(-3950 1575);
WIRE 16 -1 (-4150 1575)(-4150 1675);
WIRE 16 -1 (-2625 1675)(-4150 1675);
FORCEPROP 2 LAST SIG_NAME I3C_SPD_DDRABCD_CPU1_LVC1_SCL_R8
J 0
(-3710 1685);
DISPLAY 0.680851 (-3710 1685);
PAINT WHITE (-3710 1685);
WIRE 16 -1 (-2625 1725)(-3650 1725);
FORCEPROP 2 LAST SIG_NAME I3C_SPD_DDRABCD_CPU1_LVC1_SDA
J 0
(-3635 1735);
DISPLAY 0.680851 (-3635 1735);
PAINT WHITE (-3635 1735);
WIRE 16 -1 (-2625 1775)(-3650 1775);
FORCEPROP 2 LAST SIG_NAME PD_CHD_CPU1_DIMM2_SAA
J 0
(-3635 1785);
DISPLAY 0.680851 (-3635 1785);
PAINT WHITE (-3635 1785);
WIRE 16 -1 (-3675 1825)(-2625 1825);
WIRE 16 -1 (-2625 1925)(-3725 1925);
FORCEPROP 2 LAST SIG_NAME M_D_CPU1_ALERT_N
J 0
(-3637 1934);
DISPLAY 0.680851 (-3637 1934);
PAINT WHITE (-3637 1934);
WIRE 16 -1 (-3025 1975)(-2625 1975);
WIRE 16 -1 (-3025 2025)(-3725 2025);
FORCEPROP 2 LAST SIG_NAME RST_M_CD_CPU1_FPGA_N
J 0
(-3637 2034);
DISPLAY 0.680851 (-3637 2034);
PAINT WHITE (-3637 2034);
WIRE 16 -1 (-3025 2025)(-3025 1975);
WIRE 16 -1 (1400 4225)(1675 4225);
WIRE 16 -1 (1400 4125)(1675 4125);
WIRE 16 -1 (1400 3925)(1675 3925);
WIRE 16 -1 (1400 4025)(1675 4025);
WIRE 16 -1 (1400 3725)(1675 3725);
WIRE 16 -1 (1400 3825)(1675 3825);
WIRE 16 -1 (1400 3625)(1675 3625);
WIRE 16 -1 (1400 3425)(1675 3425);
WIRE 16 -1 (1400 3525)(1675 3525);
WIRE 16 -1 (1400 3325)(1675 3325);
WIRE 16 -1 (1400 3075)(1675 3075);
WIRE 16 -1 (1400 3175)(1675 3175);
WIRE 16 -1 (1400 2975)(1675 2975);
WIRE 16 -1 (1400 2875)(1675 2875);
WIRE 16 -1 (1400 2775)(1675 2775);
WIRE 16 -1 (1400 2675)(1675 2675);
WIRE 16 -1 (1400 2575)(1675 2575);
WIRE 16 -1 (1400 2475)(1675 2475);
WIRE 16 -1 (1400 2375)(1675 2375);
WIRE 16 -1 (1400 2275)(1675 2275);
WIRE 16 -1 (1400 4275)(1500 4275);
WIRE 16 -1 (1400 4175)(1500 4175);
WIRE 16 -1 (1400 4075)(1500 4075);
WIRE 16 -1 (1400 3125)(1500 3125);
WIRE 16 -1 (1400 3375)(1500 3375);
WIRE 16 -1 (1400 3225)(1500 3225);
WIRE 16 -1 (1400 3475)(1500 3475);
WIRE 16 -1 (1400 3575)(1500 3575);
WIRE 16 -1 (1400 3675)(1500 3675);
WIRE 16 -1 (1400 3775)(1500 3775);
WIRE 16 -1 (1400 3875)(1500 3875);
WIRE 16 -1 (1400 3975)(1500 3975);
WIRE 16 -1 (1400 2325)(1500 2325);
WIRE 16 -1 (1400 2425)(1500 2425);
WIRE 16 -1 (1400 2625)(1500 2625);
WIRE 16 -1 (1400 2525)(1500 2525);
WIRE 16 -1 (1400 2725)(1500 2725);
WIRE 16 -1 (1400 2825)(1500 2825);
WIRE 16 -1 (1400 2925)(1500 2925);
WIRE 16 -1 (1400 3025)(1500 3025);
WIRE 16 -1 (-2800 2175)(-2625 2175);
WIRE 16 -1 (-2800 2325)(-2625 2325);
WIRE 16 -1 (3475 4175)(3225 4175);
WIRE 16 -1 (3225 4225)(3225 4175);
WIRE 16 -1 (3225 4225)(3475 4225);
WIRE 16 -1 (3225 4275)(3225 4225);
WIRE 16 -1 (3475 4275)(3225 4275);
WIRE 16 -1 (-1425 3725)(-1250 3725);
WIRE 16 -1 (-1425 4175)(-1250 4175);
WIRE 16 -1 (-1425 4225)(-1250 4225);
WIRE 16 -1 (-1425 3475)(-1250 3475);
WIRE 16 -1 (3475 4125)(3225 4125);
WIRE 16 -1 (3225 4075)(3475 4075);
WIRE 16 -1 (3225 4075)(3225 4125);
WIRE 16 -1 (3225 4025)(3225 4075);
WIRE 16 -1 (3475 4025)(3225 4025);
WIRE 16 -1 (3225 3975)(3225 4025);
WIRE 16 -1 (3225 3975)(3475 3975);
WIRE 16 -1 (3225 3925)(3225 3975);
WIRE 16 -1 (3225 3925)(3475 3925);
WIRE 16 -1 (3225 3875)(3225 3925);
WIRE 16 -1 (3225 3875)(3475 3875);
WIRE 16 -1 (3225 3825)(3225 3875);
WIRE 16 -1 (3225 3825)(3475 3825);
WIRE 16 -1 (3225 3775)(3225 3825);
WIRE 16 -1 (3225 3775)(3475 3775);
WIRE 16 -1 (3225 3725)(3225 3775);
WIRE 16 -1 (3225 3725)(3475 3725);
WIRE 16 -1 (3225 3675)(3225 3725);
WIRE 16 -1 (3225 3675)(3475 3675);
WIRE 16 -1 (3225 3625)(3225 3675);
WIRE 16 -1 (3225 3625)(3475 3625);
WIRE 16 -1 (3225 3575)(3475 3575);
WIRE 16 -1 (3225 3575)(3225 3625);
WIRE 16 -1 (3225 3525)(3225 3575);
WIRE 16 -1 (3475 3525)(3225 3525);
WIRE 16 -1 (3225 3475)(3225 3525);
WIRE 16 -1 (3225 3475)(3475 3475);
WIRE 16 -1 (3225 3425)(3225 3475);
WIRE 16 -1 (3225 3425)(3475 3425);
WIRE 16 -1 (3225 3375)(3225 3425);
WIRE 16 -1 (3225 3375)(3475 3375);
WIRE 16 -1 (3225 3325)(3225 3375);
WIRE 16 -1 (3225 3325)(3475 3325);
WIRE 16 -1 (3225 3275)(3225 3325);
WIRE 16 -1 (3225 3275)(3475 3275);
WIRE 16 -1 (3225 3225)(3225 3275);
WIRE 16 -1 (3225 3225)(3475 3225);
WIRE 16 -1 (3225 3175)(3225 3225);
WIRE 16 -1 (3225 3175)(3475 3175);
WIRE 16 -1 (3225 3125)(3225 3175);
WIRE 16 -1 (3225 3125)(3475 3125);
WIRE 16 -1 (3225 3075)(3225 3125);
WIRE 16 -1 (3225 3075)(3475 3075);
WIRE 16 -1 (3475 3025)(3225 3025);
WIRE 16 -1 (3225 3025)(3225 3075);
WIRE 16 -1 (3225 2975)(3225 3025);
WIRE 16 -1 (3225 2975)(3475 2975);
WIRE 16 -1 (3225 2925)(3225 2975);
WIRE 16 -1 (3225 2925)(3475 2925);
WIRE 16 -1 (3225 2875)(3225 2925);
WIRE 16 -1 (3225 2875)(3475 2875);
WIRE 16 -1 (3225 2825)(3225 2875);
WIRE 16 -1 (3225 2825)(3475 2825);
WIRE 16 -1 (3225 2775)(3225 2825);
WIRE 16 -1 (3225 2775)(3475 2775);
WIRE 16 -1 (3225 2725)(3225 2775);
WIRE 16 -1 (3225 2725)(3475 2725);
WIRE 16 -1 (3225 2675)(3225 2725);
WIRE 16 -1 (3225 2675)(3475 2675);
WIRE 16 -1 (3225 2625)(3225 2675);
WIRE 16 -1 (3225 2625)(3475 2625);
WIRE 16 -1 (3225 2575)(3225 2625);
WIRE 16 -1 (3225 2575)(3475 2575);
WIRE 16 -1 (3475 2525)(3225 2525);
WIRE 16 -1 (3225 2525)(3225 2575);
WIRE 16 -1 (3225 2475)(3225 2525);
WIRE 16 -1 (3225 2475)(3475 2475);
WIRE 16 -1 (3225 2425)(3225 2475);
WIRE 16 -1 (3225 2425)(3475 2425);
WIRE 16 -1 (3225 2375)(3225 2425);
WIRE 16 -1 (3225 2375)(3475 2375);
WIRE 16 -1 (3225 2325)(3225 2375);
WIRE 16 -1 (3225 2325)(3475 2325);
WIRE 16 -1 (3225 2275)(3225 2325);
WIRE 16 -1 (3225 2275)(3475 2275);
WIRE 16 -1 (3225 2225)(3225 2275);
WIRE 16 -1 (3225 2225)(3475 2225);
WIRE 16 -1 (3225 2175)(3225 2225);
WIRE 16 -1 (3225 2175)(3475 2175);
WIRE 16 -1 (3225 2125)(3225 2175);
WIRE 16 -1 (3225 2125)(3475 2125);
WIRE 16 -1 (3225 2075)(3225 2125);
WIRE 16 -1 (3225 2075)(3475 2075);
WIRE 16 -1 (3475 2025)(3225 2025);
WIRE 16 -1 (3225 2025)(3225 2075);
WIRE 16 -1 (3225 1975)(3225 2025);
WIRE 16 -1 (3225 1975)(3475 1975);
WIRE 16 -1 (3225 1925)(3225 1975);
WIRE 16 -1 (3225 1925)(3475 1925);
WIRE 16 -1 (3225 1875)(3225 1925);
WIRE 16 -1 (3225 1875)(3475 1875);
WIRE 16 -1 (3225 1825)(3225 1875);
WIRE 16 -1 (3225 1825)(3475 1825);
WIRE 16 -1 (3225 1775)(3225 1825);
WIRE 16 -1 (3225 1775)(3475 1775);
WIRE 16 -1 (3225 1725)(3225 1775);
WIRE 16 -1 (3225 1725)(3475 1725);
WIRE 16 -1 (3225 1675)(3225 1725);
WIRE 16 -1 (3225 1675)(3475 1675);
WIRE 16 -1 (3225 1625)(3225 1675);
WIRE 16 -1 (3225 1625)(3475 1625);
WIRE 16 -1 (3225 1575)(3225 1625);
WIRE 16 -1 (3225 1575)(3475 1575);
WIRE 16 -1 (3475 1525)(3225 1525);
WIRE 16 -1 (3225 1525)(3225 1575);
WIRE 16 -1 (3225 1475)(3225 1525);
WIRE 16 -1 (3225 1475)(3475 1475);
WIRE 16 -1 (3225 1425)(3225 1475);
WIRE 16 -1 (3225 1425)(3475 1425);
WIRE 16 -1 (3225 1375)(3225 1425);
WIRE 16 -1 (3225 1375)(3475 1375);
WIRE 16 -1 (3225 1325)(3225 1375);
WIRE 16 -1 (3225 1325)(3475 1325);
WIRE 16 -1 (3225 1275)(3225 1325);
WIRE 16 -1 (3225 1275)(3475 1275);
WIRE 16 -1 (3225 1225)(3225 1275);
WIRE 16 -1 (3225 1225)(3475 1225);
WIRE 16 -1 (3225 1175)(3225 1225);
WIRE 16 -1 (3225 1175)(3475 1175);
WIRE 16 -1 (3225 1125)(3225 1175);
WIRE 16 -1 (3225 1125)(3475 1125);
WIRE 16 -1 (3225 1075)(3225 1125);
WIRE 16 -1 (3225 1075)(3475 1075);
WIRE 16 -1 (3225 1025)(3225 1075);
WIRE 16 -1 (3225 1025)(3475 1025);
WIRE 16 -1 (-1425 3275)(-1250 3275);
WIRE 16 -1 (-1425 3325)(-1250 3325);
WIRE 16 -1 (-1425 2775)(-1250 2775);
WIRE 16 -1 (-1425 2425)(-1250 2425);
WIRE 16 -1 (-1425 2375)(-1250 2375);
WIRE 16 -1 (-1425 2325)(-1250 2325);
WIRE 16 -1 (-1425 1875)(-1250 1875);
WIRE 16 -1 (-2625 1025)(-3725 1025);
FORCEPROP 2 LAST SIG_NAME TP_CHD_CPU1_DIMM2_FRU_0
J 0
(-3637 1034);
DISPLAY 0.680851 (-3637 1034);
PAINT WHITE (-3637 1034);
WIRE 16 -1 (-2625 1075)(-3725 1075);
FORCEPROP 2 LAST SIG_NAME TP_CHD_CPU1_DIMM2_FRU_1
J 0
(-3637 1084);
DISPLAY 0.680851 (-3637 1084);
PAINT WHITE (-3637 1084);
WIRE 16 -1 (-2625 1125)(-3725 1125);
FORCEPROP 2 LAST SIG_NAME TP_CHD_CPU1_DIMM2_FRU_2
J 0
(-3637 1134);
DISPLAY 0.680851 (-3637 1134);
PAINT WHITE (-3637 1134);
WIRE 16 -1 (-2625 1175)(-3725 1175);
FORCEPROP 2 LAST SIG_NAME TP_CHD_CPU1_DIMM2_FRU_3
J 0
(-3637 1184);
DISPLAY 0.680851 (-3637 1184);
PAINT WHITE (-3637 1184);
WIRE 16 -1 (-2625 1225)(-3725 1225);
FORCEPROP 2 LAST SIG_NAME TP_CHD_CPU1_DIMM2_FRU_4
J 0
(-3637 1234);
DISPLAY 0.680851 (-3637 1234);
PAINT WHITE (-3637 1234);
WIRE 16 -1 (-2625 1275)(-3725 1275);
FORCEPROP 2 LAST SIG_NAME TP_CHD_CPU1_DIMM2_FRU_5
J 0
(-3637 1284);
DISPLAY 0.680851 (-3637 1284);
PAINT WHITE (-3637 1284);
WIRE 16 -1 (-2625 1325)(-3725 1325);
FORCEPROP 2 LAST SIG_NAME TP_CHD_CPU1_DIMM2_FRU_6
J 0
(-3637 1334);
DISPLAY 0.680851 (-3637 1334);
PAINT WHITE (-3637 1334);
WIRE 16 -1 (-2625 1425)(-3725 1425);
FORCEPROP 2 LAST SIG_NAME PWRGD_CHD_CPU1_DIMM2
J 0
(-3637 1434);
DISPLAY 0.680851 (-3637 1434);
PAINT WHITE (-3637 1434);
WIRE 16 -1 (-2625 3425)(-3725 3425);
FORCEPROP 2 LAST SIG_NAME M_D_CPU1_SB_PAR
J 0
(-3637 3434);
DISPLAY 0.680851 (-3637 3434);
PAINT WHITE (-3637 3434);
WIRE 16 -1 (-2625 3475)(-3725 3475);
FORCEPROP 2 LAST SIG_NAME M_D_CPU1_SA_PAR
J 0
(-3637 3484);
DISPLAY 0.680851 (-3637 3484);
PAINT WHITE (-3637 3484);
WIRE 16 -1 (-2625 825)(-3725 825);
FORCEPROP 2 LAST SIG_NAME M_D_CPU1_SB_RSP<1>
J 0
(-3637 834);
DISPLAY 0.680851 (-3637 834);
PAINT WHITE (-3637 834);
WIRE 16 -1 (-2625 875)(-3725 875);
FORCEPROP 2 LAST SIG_NAME M_D_CPU1_SA_RSP<1>
J 0
(-3637 884);
DISPLAY 0.680851 (-3637 884);
PAINT WHITE (-3637 884);
WIRE 16 -1 (-1425 1075)(-1250 1075);
WIRE 16 -1 (-1425 1125)(-1250 1125);
WIRE 16 -1 (-1425 1175)(-1250 1175);
WIRE 16 -1 (-1425 1225)(-1250 1225);
WIRE 16 -1 (-1425 1325)(-1250 1325);
WIRE 16 -1 (-1425 1375)(-1250 1375);
WIRE 16 -1 (-1425 1425)(-1250 1425);
WIRE 16 -1 (-1425 1475)(-1250 1475);
WIRE 16 -1 (-1425 1525)(-1250 1525);
WIRE 16 -1 (-1425 1575)(-1250 1575);
WIRE 16 -1 (-1425 1625)(-1250 1625);
WIRE 16 -1 (-1425 1675)(-1250 1675);
WIRE 16 -1 (-1425 1725)(-1250 1725);
WIRE 16 -1 (-1425 1775)(-1250 1775);
WIRE 16 -1 (-1425 1825)(-1250 1825);
WIRE 16 -1 (-1425 1925)(-1250 1925);
WIRE 16 -1 (-1425 1975)(-1250 1975);
WIRE 16 -1 (-1425 2025)(-1250 2025);
WIRE 16 -1 (-1425 2075)(-1250 2075);
WIRE 16 -1 (-1425 2125)(-1250 2125);
WIRE 16 -1 (-1425 2175)(-1250 2175);
WIRE 16 -1 (-1425 2225)(-1250 2225);
WIRE 16 -1 (-1425 2275)(-1250 2275);
WIRE 16 -1 (-1425 2475)(-1250 2475);
WIRE 16 -1 (-1425 2525)(-1250 2525);
WIRE 16 -1 (-1425 2575)(-1250 2575);
WIRE 16 -1 (-1425 2625)(-1250 2625);
WIRE 16 -1 (-1425 2725)(-1250 2725);
WIRE 16 -1 (-1425 2825)(-1250 2825);
WIRE 16 -1 (-1425 2875)(-1250 2875);
WIRE 16 -1 (-1425 2925)(-1250 2925);
WIRE 16 -1 (-1425 2975)(-1250 2975);
WIRE 16 -1 (-1425 3025)(-1250 3025);
WIRE 16 -1 (-1425 3075)(-1250 3075);
WIRE 16 -1 (-1425 3125)(-1250 3125);
WIRE 16 -1 (-1425 3175)(-1250 3175);
WIRE 16 -1 (-1425 3225)(-1250 3225);
WIRE 16 -1 (-1425 3375)(-1250 3375);
WIRE 16 -1 (-1425 3425)(-1250 3425);
WIRE 16 -1 (-1425 3525)(-1250 3525);
WIRE 16 -1 (-1425 3575)(-1250 3575);
WIRE 16 -1 (-1425 3625)(-1250 3625);
WIRE 16 -1 (-1425 3675)(-1250 3675);
WIRE 16 -1 (-1425 3775)(-1250 3775);
WIRE 16 -1 (-1425 3825)(-1250 3825);
WIRE 16 -1 (-1425 3875)(-1250 3875);
WIRE 16 -1 (-1425 3925)(-1250 3925);
WIRE 16 -1 (-1425 3975)(-1250 3975);
WIRE 16 -1 (-1425 4025)(-1250 4025);
WIRE 16 -1 (-1425 4075)(-1250 4075);
WIRE 16 -1 (-1425 4125)(-1250 4125);
WIRE 16 -1 (-2625 3175)(-3725 3175);
FORCEPROP 2 LAST SIG_NAME M_D_CPU1_SB_CS_N<3>
J 0
(-3637 3184);
DISPLAY 0.680851 (-3637 3184);
PAINT WHITE (-3637 3184);
WIRE 16 -1 (-2625 3325)(-3725 3325);
FORCEPROP 2 LAST SIG_NAME M_D_CPU1_SA_CS_N<3>
J 0
(-3637 3334);
DISPLAY 0.680851 (-3637 3334);
PAINT WHITE (-3637 3334);
WIRE 16 -1 (-2625 3125)(-3725 3125);
FORCEPROP 2 LAST SIG_NAME M_D_CPU1_SB_CS_N<2>
J 0
(-3637 3134);
DISPLAY 0.680851 (-3637 3134);
PAINT WHITE (-3637 3134);
WIRE 16 -1 (-2625 3275)(-3725 3275);
FORCEPROP 2 LAST SIG_NAME M_D_CPU1_SA_CS_N<2>
J 0
(-3637 3284);
DISPLAY 0.680851 (-3637 3284);
PAINT WHITE (-3637 3284);
WIRE 16 -1 (-2625 3025)(-3725 3025);
FORCEPROP 2 LAST SIG_NAME M_D_CPU1_CLK_DP<1>
J 0
(-3637 3034);
DISPLAY 0.680851 (-3637 3034);
PAINT WHITE (-3637 3034);
WIRE 16 -1 (-2625 2975)(-3725 2975);
FORCEPROP 2 LAST SIG_NAME M_D_CPU1_CLK_DN<1>
J 0
(-3637 2984);
DISPLAY 0.680851 (-3637 2984);
PAINT WHITE (-3637 2984);
WIRE 16 -1 (-2800 2075)(-2625 2075);
WIRE 16 -1 (-2800 2125)(-2625 2125);
WIRE 16 -1 (-2800 2225)(-2625 2225);
WIRE 16 -1 (-2800 2275)(-2625 2275);
WIRE 16 -1 (-2800 2375)(-2625 2375);
WIRE 16 -1 (-2800 2525)(-2625 2525);
WIRE 16 -1 (-2800 2625)(-2625 2625);
WIRE 16 -1 (-2800 2675)(-2625 2675);
WIRE 16 -1 (-2800 2775)(-2625 2775);
WIRE 16 -1 (-2800 2825)(-2625 2825);
WIRE 16 -1 (-2800 3875)(-2625 3875);
WIRE 16 -1 (-2800 4275)(-2625 4275);
WIRE 16 -1 (-2800 3825)(-2625 3825);
WIRE 16 -1 (-2800 4225)(-2625 4225);
WIRE 16 -1 (-2800 3775)(-2625 3775);
WIRE 16 -1 (-2800 4175)(-2625 4175);
WIRE 16 -1 (-2800 3725)(-2625 3725);
WIRE 16 -1 (-2800 4125)(-2625 4125);
WIRE 16 -1 (-2800 3675)(-2625 3675);
WIRE 16 -1 (-2800 4075)(-2625 4075);
WIRE 16 -1 (-2800 3625)(-2625 3625);
WIRE 16 -1 (-2800 4025)(-2625 4025);
WIRE 16 -1 (-2800 3575)(-2625 3575);
WIRE 16 -1 (-2800 3975)(-2625 3975);
WIRE 16 -1 (-2800 2425)(-2625 2425);
WIRE 16 -1 (-2800 2575)(-2625 2575);
WIRE 16 -1 (-2800 2725)(-2625 2725);
WIRE 16 -1 (-2800 2875)(-2625 2875);
WIRE 16 -1 (-1425 4275)(-1250 4275);
WIRE 16 -1 (4675 975)(4925 975);
WIRE 16 -1 (4925 1025)(4925 975);
WIRE 16 -1 (4675 1025)(4925 1025);
WIRE 16 -1 (4675 1125)(4925 1125);
WIRE 16 -1 (4925 1125)(4925 1025);
WIRE 16 -1 (4675 1175)(4925 1175);
WIRE 16 -1 (4925 1175)(4925 1125);
WIRE 16 -1 (4675 1225)(4925 1225);
WIRE 16 -1 (4925 1175)(4925 1225);
WIRE 16 -1 (4675 1275)(4925 1275);
WIRE 16 -1 (4925 1275)(4925 1225);
WIRE 16 -1 (4675 1325)(4925 1325);
WIRE 16 -1 (4925 1325)(4925 1275);
WIRE 16 -1 (4675 1375)(4925 1375);
WIRE 16 -1 (4925 1375)(4925 1325);
WIRE 16 -1 (4675 1425)(4925 1425);
WIRE 16 -1 (4925 1425)(4925 1375);
WIRE 16 -1 (4675 1475)(4925 1475);
WIRE 16 -1 (4925 1475)(4925 1425);
WIRE 16 -1 (4675 1525)(4925 1525);
WIRE 16 -1 (4925 1525)(4925 1475);
WIRE 16 -1 (4925 1575)(4925 1525);
WIRE 16 -1 (4925 1575)(4675 1575);
WIRE 16 -1 (4925 1625)(4675 1625);
WIRE 16 -1 (4925 1625)(4925 1575);
WIRE 16 -1 (4925 1675)(4675 1675);
WIRE 16 -1 (4925 1675)(4925 1625);
WIRE 16 -1 (4675 1725)(4925 1725);
WIRE 16 -1 (4925 1675)(4925 1725);
WIRE 16 -1 (4925 1775)(4675 1775);
WIRE 16 -1 (4925 1725)(4925 1775);
WIRE 16 -1 (4925 1825)(4675 1825);
WIRE 16 -1 (4925 1825)(4925 1775);
WIRE 16 -1 (4925 1875)(4675 1875);
WIRE 16 -1 (4925 1875)(4925 1825);
WIRE 16 -1 (4925 1925)(4675 1925);
WIRE 16 -1 (4925 1925)(4925 1875);
WIRE 16 -1 (4675 1975)(4925 1975);
WIRE 16 -1 (4925 1975)(4925 1925);
WIRE 16 -1 (4675 2025)(4925 2025);
WIRE 16 -1 (4925 2025)(4925 1975);
WIRE 16 -1 (4925 2025)(4925 2075);
WIRE 16 -1 (4675 2075)(4925 2075);
WIRE 16 -1 (4675 2125)(4925 2125);
WIRE 16 -1 (4925 2125)(4925 2075);
WIRE 16 -1 (4675 2175)(4925 2175);
WIRE 16 -1 (4925 2175)(4925 2125);
WIRE 16 -1 (4675 2225)(4925 2225);
WIRE 16 -1 (4925 2225)(4925 2175);
WIRE 16 -1 (4675 2275)(4925 2275);
WIRE 16 -1 (4925 2275)(4925 2225);
WIRE 16 -1 (4675 2325)(4925 2325);
WIRE 16 -1 (4925 2325)(4925 2275);
WIRE 16 -1 (4925 2375)(4675 2375);
WIRE 16 -1 (4925 2375)(4925 2325);
WIRE 16 -1 (4925 2425)(4675 2425);
WIRE 16 -1 (4925 2425)(4925 2375);
WIRE 16 -1 (4675 2475)(4925 2475);
WIRE 16 -1 (4925 2475)(4925 2425);
WIRE 16 -1 (4675 2525)(4925 2525);
WIRE 16 -1 (4925 2525)(4925 2475);
WIRE 16 -1 (4925 2525)(4925 2575);
WIRE 16 -1 (4675 2575)(4925 2575);
WIRE 16 -1 (4675 2625)(4925 2625);
WIRE 16 -1 (4925 2625)(4925 2575);
WIRE 16 -1 (4675 2675)(4925 2675);
WIRE 16 -1 (4925 2675)(4925 2625);
WIRE 16 -1 (4675 2725)(4925 2725);
WIRE 16 -1 (4925 2725)(4925 2675);
WIRE 16 -1 (4675 2775)(4925 2775);
WIRE 16 -1 (4925 2775)(4925 2725);
WIRE 16 -1 (4675 2825)(4925 2825);
WIRE 16 -1 (4925 2825)(4925 2775);
WIRE 16 -1 (4925 2875)(4675 2875);
WIRE 16 -1 (4925 2875)(4925 2825);
WIRE 16 -1 (4925 2925)(4675 2925);
WIRE 16 -1 (4925 2925)(4925 2875);
WIRE 16 -1 (4675 2975)(4925 2975);
WIRE 16 -1 (4925 2975)(4925 2925);
WIRE 16 -1 (4675 3025)(4925 3025);
WIRE 16 -1 (4925 3025)(4925 2975);
WIRE 16 -1 (4925 3025)(4925 3075);
WIRE 16 -1 (4675 3075)(4925 3075);
WIRE 16 -1 (4675 3125)(4925 3125);
WIRE 16 -1 (4925 3125)(4925 3075);
WIRE 16 -1 (4675 3175)(4925 3175);
WIRE 16 -1 (4925 3175)(4925 3125);
WIRE 16 -1 (4675 3225)(4925 3225);
WIRE 16 -1 (4925 3225)(4925 3175);
WIRE 16 -1 (4675 3275)(4925 3275);
WIRE 16 -1 (4925 3275)(4925 3225);
WIRE 16 -1 (4675 3325)(4925 3325);
WIRE 16 -1 (4925 3325)(4925 3275);
WIRE 16 -1 (4925 3375)(4675 3375);
WIRE 16 -1 (4925 3375)(4925 3325);
WIRE 16 -1 (4925 3425)(4675 3425);
WIRE 16 -1 (4925 3425)(4925 3375);
WIRE 16 -1 (4675 3475)(4925 3475);
WIRE 16 -1 (4925 3475)(4925 3425);
WIRE 16 -1 (4675 3525)(4925 3525);
WIRE 16 -1 (4925 3525)(4925 3475);
WIRE 16 -1 (4675 3575)(4925 3575);
WIRE 16 -1 (4925 3525)(4925 3575);
WIRE 16 -1 (4925 3625)(4925 3575);
WIRE 16 -1 (4675 3625)(4925 3625);
WIRE 16 -1 (4675 3675)(4925 3675);
WIRE 16 -1 (4925 3675)(4925 3625);
WIRE 16 -1 (4675 3725)(4925 3725);
WIRE 16 -1 (4925 3725)(4925 3675);
WIRE 16 -1 (4675 3775)(4925 3775);
WIRE 16 -1 (4925 3775)(4925 3725);
WIRE 16 -1 (4675 3825)(4925 3825);
WIRE 16 -1 (4925 3825)(4925 3775);
WIRE 16 -1 (4675 3875)(4925 3875);
WIRE 16 -1 (4925 3875)(4925 3825);
WIRE 16 -1 (4675 3925)(4925 3925);
WIRE 16 -1 (4925 3925)(4925 3875);
WIRE 16 -1 (4675 3975)(4925 3975);
WIRE 16 -1 (4925 3975)(4925 3925);
WIRE 16 -1 (4675 4025)(4925 4025);
WIRE 16 -1 (4925 4025)(4925 3975);
WIRE 16 -1 (4675 4075)(4925 4075);
WIRE 16 -1 (4925 4075)(4925 4025);
WIRE 16 -1 (4925 4125)(4925 4075);
WIRE 16 -1 (4675 4125)(4925 4125);
WIRE 16 -1 (4675 4175)(4925 4175);
WIRE 16 -1 (4925 4175)(4925 4125);
WIRE 16 -1 (4675 4225)(4925 4225);
WIRE 16 -1 (4925 4225)(4925 4175);
WIRE 16 -1 (4925 4275)(4925 4225);
WIRE 16 -1 (4675 4275)(4925 4275);
WIRE 16 -1 (-2625 325)(-3725 325);
FORCEPROP 2 LAST SIG_NAME PD_CHD_CPU1_DIMM2_SAA
J 0
(-3637 334);
DISPLAY 0.680851 (-3637 334);
PAINT WHITE (-3637 334);
WIRE 16 -1 (-2625 225)(-2625 325);
WIRE 16 -1 (1525 625)(1525 500);
WIRE 16 -1 (2150 625)(1525 625);
WIRE 16 -1 (2150 500)(2150 625);
WIRE 16 -1 (1525 150)(1525 300);
WIRE 16 -1 (2150 150)(1525 150);
WIRE 16 -1 (2150 150)(2150 300);
DOT 1 (3225 3175);
DOT 1 (3225 2225);
DOT 1 (3225 3225);
DOT 1 (3225 3425);
DOT 1 (3225 3525);
DOT 1 (3225 3625);
DOT 1 (4925 4225);
DOT 1 (4925 4125);
DOT 1 (4925 4175);
DOT 1 (4925 4025);
DOT 1 (4925 4075);
DOT 1 (4925 3975);
DOT 1 (4925 3925);
DOT 1 (4925 3875);
DOT 1 (4925 3775);
DOT 1 (4925 3825);
DOT 1 (4925 3725);
DOT 1 (4925 3625);
DOT 1 (4925 3675);
DOT 1 (4925 3475);
DOT 1 (4925 3575);
DOT 1 (4925 3525);
DOT 1 (4925 3425);
DOT 1 (4925 3375);
DOT 1 (4925 3225);
DOT 1 (4925 3325);
DOT 1 (4925 3275);
DOT 1 (4925 3125);
DOT 1 (4925 3175);
DOT 1 (4925 3075);
DOT 1 (4925 3025);
DOT 1 (4925 2975);
DOT 1 (4925 2875);
DOT 1 (4925 2925);
DOT 1 (4925 2825);
DOT 1 (4925 2775);
DOT 1 (4925 2725);
DOT 1 (4925 2575);
DOT 1 (4925 2675);
DOT 1 (4925 2625);
DOT 1 (4925 2525);
DOT 1 (4925 2475);
DOT 1 (4925 2325);
DOT 1 (4925 2425);
DOT 1 (4925 2375);
DOT 1 (4925 2275);
DOT 1 (4925 2225);
DOT 1 (4925 2075);
DOT 1 (4925 2175);
DOT 1 (4925 2125);
DOT 1 (4925 1975);
DOT 1 (4925 2025);
DOT 1 (4925 1925);
DOT 1 (4925 1875);
DOT 1 (4925 1825);
DOT 1 (4925 1725);
DOT 1 (4925 1775);
DOT 1 (4925 1675);
DOT 1 (4925 1625);
DOT 1 (4925 1575);
DOT 1 (4925 1425);
DOT 1 (4925 1525);
DOT 1 (4925 1475);
DOT 1 (4925 1375);
DOT 1 (4925 1325);
DOT 1 (4925 1175);
DOT 1 (4925 1275);
DOT 1 (4925 1225);
DOT 1 (4925 1125);
DOT 1 (3225 4275);
DOT 1 (3225 4225);
DOT 1 (3225 4075);
DOT 1 (3225 4025);
DOT 1 (3225 3975);
DOT 1 (3225 3925);
DOT 1 (3225 3875);
DOT 1 (3225 3825);
DOT 1 (3225 3775);
DOT 1 (3225 3725);
DOT 1 (3225 3675);
DOT 1 (3225 3575);
DOT 1 (3225 3475);
DOT 1 (3225 3375);
DOT 1 (3225 3325);
DOT 1 (3225 3275);
DOT 1 (3225 3125);
DOT 1 (3225 3075);
DOT 1 (3225 3025);
DOT 1 (3225 2975);
DOT 1 (3225 2925);
DOT 1 (3225 2875);
DOT 1 (3225 2825);
DOT 1 (3225 2775);
DOT 1 (3225 2725);
DOT 1 (3225 2675);
DOT 1 (3225 2625);
DOT 1 (3225 2575);
DOT 1 (3225 2475);
DOT 1 (3225 2525);
DOT 1 (3225 2425);
DOT 1 (3225 2375);
DOT 1 (3225 2325);
DOT 1 (3225 2275);
DOT 1 (3225 2175);
DOT 1 (3225 2125);
DOT 1 (3225 2075);
DOT 1 (3225 2025);
DOT 1 (3225 1975);
DOT 1 (3225 1925);
DOT 1 (3225 1875);
DOT 1 (3225 1825);
DOT 1 (3225 1775);
DOT 1 (3225 1725);
DOT 1 (3225 1675);
DOT 1 (3225 1625);
DOT 1 (3225 1575);
DOT 1 (3225 1525);
DOT 1 (3225 1475);
DOT 1 (3225 1425);
DOT 1 (3225 1375);
DOT 1 (3225 1325);
DOT 1 (3225 1275);
DOT 1 (3225 1225);
DOT 1 (3225 1175);
DOT 1 (3225 1125);
DOT 1 (3225 1075);
DOT 1 (3225 1025);
DOT 1 (2150 150);
DOT 1 (1525 625);
DOT 1 (4925 1025);
DOT 1 (4925 975);
DOT 1 (4925 925);
FORCENOTE
20210728 MODIFY FOR GT
(-4100 4950) 0;
DISPLAY LEFT (-4100 4950);
DISPLAY 2.510638 (-4100 4950);
PAINT PINK (-4100 4950);
QUIT
